G04 ================== begin FILE IDENTIFICATION RECORD ==================*
G04 Layout Name:  12433-1M.brd*
G04 Film Name:    L4*
G04 File Format:  Gerber RS274X*
G04 File Origin:  Cadence Allegro 16.2-S037*
G04 Origin Date:  Fri Dec 07 18:55:13 2012*
G04 *
G04 Layer:  VIA CLASS/BOTTOM*
G04 Layer:  PIN/BOTTOM*
G04 Layer:  ETCH/BOTTOM*
G04 Layer:  DRAWING FORMAT/LAYER_PCB_STORY*
G04 Layer:  DRAWING FORMAT/LAYER_L4*
G04 *
G04 Offset:    (0.00 0.00)*
G04 Mirror:    No*
G04 Mode:      Positive*
G04 Rotation:  0*
G04 FullContactRelief:  No*
G04 UndefLineWidth:     6.00*
G04 ================== end FILE IDENTIFICATION RECORD ====================*
%FSLAX35Y35*MOIN*%
%IR0*IPPOS*OFA0.00000B0.00000*MIA0B0*SFA1.00000B1.00000*%
%ADD10C,.01*%
%ADD16C,.022*%
%ADD15C,.05*%
%ADD12C,.028*%
%ADD13C,.056*%
%ADD17C,.057*%
%ADD11R,.05X.05*%
%ADD14C,.315*%
%ADD18C,.375*%
%ADD19C,.02*%
%ADD20C,.04*%
%ADD21C,.025*%
%ADD22C,.006*%
%ADD23C,.0055*%
%ADD25C,.05204*%
%ADD26C,.08004*%
%ADD29C,.08104*%
%ADD30C,.04604*%
%ADD31C,.07404*%
%ADD24R,.13204X.13204*%
%ADD33C,.15006*%
%ADD32C,.12306*%
%ADD35C,.16606*%
%ADD34C,.13906*%
%ADD28C,.33904*%
%ADD27C,.39904*%
G75*
%LPD*%
G75*
G36*
G01X203692Y410715D02*
X203404Y43982D01*
G02X202756Y42371I-648J-675D01*
G01X72835D01*
G03X65897Y35433I0J-6938D01*
G01Y3937D01*
G02X64961Y3001I-936J0D01*
G01X3937D01*
G02X3001Y3937I0J936D01*
G01Y1328776D01*
G02X3731Y1329002I400J0D01*
G03Y1348164I13985J9581D01*
G02X3001Y1348390I-330J226D01*
G01Y1964567D01*
G02X3937Y1965503I936J0D01*
G01X64961D01*
G02X65897Y1964567I0J-936D01*
G01Y1933071D01*
G03X72835Y1926133I6938J0D01*
G01X202756D01*
G02X203692Y1925197I0J-936D01*
G01Y525539D01*
G02X202998Y525268I-400J0D01*
G03X199322Y521590I-1909J-1768D01*
G02X199337Y521017I-271J-294D01*
G03X203013Y517334I1862J-1817D01*
G02X203692Y517047I279J-287D01*
G01Y484438D01*
G02X203009Y484155I-400J0D01*
G01X200673Y486492D01*
G02X200761Y487124I283J283D01*
G03X198374Y491746I-1260J2277D01*
G02X197802Y492107I-172J361D01*
G01X197805Y495907D01*
G02X198481Y496239I397J46D01*
G03Y499961I1819J1861D01*
G02X197802Y500247I-279J286D01*
G01Y503459D01*
G02X198414Y503798I400J0D01*
G03Y508202I1386J2202D01*
G02X197802Y508541I-212J339D01*
G01Y511275D01*
G02X198454Y511584I400J-1D01*
G03Y515616I1646J2016D01*
G02X197802Y515925I-252J310D01*
G01Y529163D01*
X184882Y542082D01*
X184887Y542170D01*
G03X180401Y543007I-2299J118D01*
G02X179739Y542850I-379J126D01*
G01X161676Y560912D01*
X161789Y561052D01*
G03X158458Y560791I-1789J1448D01*
G01X158524Y560731D01*
Y560455D01*
G02X157841Y560172I-400J0D01*
G01X152802Y565212D01*
Y579188D01*
G02X153409Y579530I400J0D01*
G03Y583470I1191J1970D01*
G02X152802Y583812I-207J342D01*
G01Y585213D01*
X156681Y589093D01*
G02X157302Y589023I283J-283D01*
G03X160477Y592198I1948J1227D01*
G02X160407Y592819I213J338D01*
G01X185276Y617688D01*
Y642312D01*
X182576Y645012D01*
Y689412D01*
X173776Y698212D01*
Y726838D01*
X169602Y731013D01*
Y761089D01*
X183802Y775289D01*
Y947113D01*
X185652Y948963D01*
Y984837D01*
X181476Y989012D01*
Y999112D01*
X150476Y1030112D01*
Y1095112D01*
X143976Y1101612D01*
Y1418731D01*
X144042Y1418791D01*
G03X142501Y1422802I-1542J1709D01*
G02X142102Y1423202I1J400D01*
G01Y1441466D01*
X149019Y1448384D01*
G02X149702Y1448101I283J-283D01*
G01Y1440812D01*
G03X149794Y1440557I400J0D01*
G02X149784Y1440035I-308J-255D01*
G03X153795Y1438320I1716J-1535D01*
G01X153801Y1438394D01*
X157702Y1442295D01*
Y1445529D01*
X157766Y1445589D01*
G03X158600Y1447602I-1766J1911D01*
G01X158597Y1447690D01*
X159202Y1448295D01*
Y1453249D01*
X159250Y1453305D01*
G03X155753Y1456299I-1750J1495D01*
G02X155056Y1456485I-304J260D01*
G03X154731Y1457340I-2557J-483D01*
G01X154702Y1457388D01*
Y1457986D01*
X160702Y1463986D01*
Y1465827D01*
X160710Y1465854D01*
G03X156272Y1465923I-2209J646D01*
G01X156300Y1465812D01*
X150298Y1459810D01*
Y1458202D01*
X149612D01*
X146902Y1460912D01*
Y1460914D01*
X114364Y1493452D01*
X113423D01*
X113396Y1493460D01*
G03X112566Y1488955I-645J-2210D01*
G01X112639Y1488949D01*
X142498Y1459090D01*
Y1459088D01*
X147788Y1453798D01*
X147857D01*
X147959Y1453551D01*
X137698Y1443290D01*
Y1418302D01*
G02X137047Y1417991I-400J0D01*
G03X136638Y1418255I-1446J-1791D01*
G02X136475Y1418818I180J357D01*
G03X135863Y1421855I-1975J1182D01*
G02X135817Y1422460I237J322D01*
G01X136302Y1422944D01*
Y1439987D01*
G03X131888Y1442465I-2503J712D01*
G01X131828Y1442400D01*
X124985D01*
X122690Y1440106D01*
X122602Y1440109D01*
G03X119900Y1437407I-102J-2600D01*
G01X119903Y1437319D01*
X119486Y1436902D01*
X118971D01*
X118911Y1436966D01*
G03X115139Y1433381I-1911J-1766D01*
G02X114853Y1432702I-286J-279D01*
G01X110795D01*
X109894Y1431801D01*
X109820Y1431795D01*
G03X112272Y1429130I180J-2295D01*
G01X112299Y1429298D01*
X122205D01*
X127705Y1434798D01*
X130449D01*
X130505Y1434750D01*
G03X132425Y1434238I1495J1750D01*
G02X132898Y1433844I73J-393D01*
G01X132880Y1424336D01*
X129472Y1420928D01*
Y1414251D01*
X129424Y1414195D01*
G03X129478Y1411143I1750J-1496D01*
G01Y1410675D01*
G02X129022Y1410279I-400J0D01*
G03X127158Y1406291I-322J-2279D01*
G01X127224Y1406231D01*
Y1256330D01*
G02X126541Y1256047I-400J0D01*
G01X125253Y1257335D01*
X125267Y1257435D01*
G03X122319Y1260383I-2575J373D01*
G01X122219Y1260369D01*
X121794Y1260794D01*
X121799Y1260882D01*
G03X119618Y1258701I-2299J118D01*
G01X119706Y1258706D01*
X120067Y1258344D01*
X119838Y1258116D01*
X119722Y1258154D01*
G03X119118Y1253669I-722J-2186D01*
G01X119206Y1253674D01*
X122524Y1250356D01*
Y1249745D01*
X122443Y1249685D01*
G03Y1245515I1557J-2085D01*
G01X122524Y1245455D01*
Y1096330D01*
G02X121841Y1096047I-400J0D01*
G01X89976Y1127912D01*
Y1145112D01*
X84976Y1150112D01*
Y1333312D01*
X43676Y1374612D01*
Y1411412D01*
X41722Y1413366D01*
Y1431743D01*
X30802Y1442664D01*
Y1490887D01*
X22822Y1498866D01*
Y1504917D01*
G02X23530Y1505172I400J0D01*
G03Y1515772I6391J5300D01*
G02X22822Y1516027I-308J255D01*
G01Y1633732D01*
X26428Y1637337D01*
Y1757139D01*
X26924Y1757636D01*
G02X27606Y1757381I283J-283D01*
G03X31556Y1761331I3693J257D01*
G02X31301Y1762013I28J399D01*
G01X37112Y1767824D01*
X38912D01*
X45094Y1774006D01*
X45182Y1774001D01*
G03X43001Y1776182I118J2299D01*
G01X43006Y1776094D01*
X42055Y1775143D01*
G02X41376Y1775369I-283J282D01*
G03X38431Y1772424I-2576J-369D01*
G02X38657Y1771745I-56J-396D01*
G01X37688Y1770776D01*
X35888D01*
X25359Y1760247D01*
G02X24676Y1760530I-283J283D01*
G01Y1761099D01*
G02X25065Y1761499I400J0D01*
G03X22701Y1763682I-65J2301D01*
G01X22706Y1763594D01*
X21724Y1762612D01*
Y1708671D01*
G02X21009Y1708423I-400J-1D01*
G03X18776Y1709263I-1810J-1423D01*
G02X18302Y1709656I-74J393D01*
G01Y1769023D01*
X38989Y1789709D01*
X39077Y1789706D01*
G03X36579Y1792204I102J2600D01*
G01X36582Y1792116D01*
X14900Y1770433D01*
Y1709142D01*
G02X14420Y1708750I-400J0D01*
G03Y1703650I-520J-2550D01*
G02X14900Y1703258I80J-392D01*
G01Y1692021D01*
G02X14322Y1691663I-400J0D01*
G03X11090Y1688954I-1022J-2063D01*
G01X11098Y1688927D01*
Y1651495D01*
G02X10669Y1651096I-400J0D01*
G03Y1646504I-169J-2296D01*
G02X11098Y1646105I29J-399D01*
G01Y1645212D01*
X9098Y1643212D01*
Y1492312D01*
X7020Y1490233D01*
Y1379867D01*
X61698Y1325188D01*
Y1167426D01*
X58298Y1164026D01*
Y1145326D01*
X38198Y1125226D01*
Y1109226D01*
X37036Y1108064D01*
G03Y1103536I2264J-2264D01*
G01X37765Y1102808D01*
G02X37485Y1102125I-283J-283D01*
G03X35958Y1098114I15J-2302D01*
G01X36024Y1098054D01*
Y1000145D01*
X35943Y1000085D01*
G03Y995915I1557J-2085D01*
G01X36024Y995855D01*
Y993592D01*
X35957Y993532D01*
G03X38024Y989018I1743J-1932D01*
G02X38474Y988621I50J-397D01*
G01Y933867D01*
X38434Y933813D01*
G03Y929985I2566J-1914D01*
G01X38474Y929931D01*
Y910047D01*
X46398Y902122D01*
Y882374D01*
X48798Y879974D01*
Y848674D01*
X53598Y843874D01*
Y828818D01*
G02X52903Y828549I-400J1D01*
G03X49450Y825505I-1704J-1548D01*
G01X49498Y825449D01*
Y781405D01*
X38092Y769999D01*
Y753501D01*
X40698Y750895D01*
Y702395D01*
X43155Y699939D01*
G02X43113Y699337I-283J-283D01*
G03X42238Y697926I1387J-1837D01*
G01Y697925D01*
X42226Y697864D01*
X39748Y695386D01*
Y692887D01*
X9244Y662384D01*
X9243D01*
X7354Y660495D01*
Y470582D01*
X7352Y470580D01*
Y445995D01*
X7354Y445993D01*
Y317011D01*
X14224Y310142D01*
Y238746D01*
X28803Y224167D01*
G02X28791Y223589I-282J-283D01*
G03X31299Y217164I2508J-2723D01*
G01X31500D01*
Y214568D01*
X31299D01*
G03X31020Y207175I0J-3702D01*
G01X31094Y207169D01*
X31288Y206975D01*
X30948Y206636D01*
Y179668D01*
X30882Y179608D01*
G03X34195Y176428I1543J-1708D01*
G01X34255Y176500D01*
X36212D01*
X37006Y175706D01*
X37001Y175618D01*
G03X40657Y173641I2299J-118D01*
G02X41264Y173467I236J-323D01*
G03X43202Y172032I2136J858D01*
G01X43275Y172025D01*
X44098Y171201D01*
Y166495D01*
X46122Y164471D01*
Y79971D01*
X61480Y64613D01*
X61420Y64485D01*
G03X65250Y64995I2080J-985D01*
G01X65202Y65051D01*
Y65587D01*
X65290Y65647D01*
G03X62338Y69146I-1290J1907D01*
G02X61766Y69140I-289J277D01*
G01X49526Y81381D01*
Y150559D01*
G02X49925Y150959I400J0D01*
G03X51559Y151641I-1J2302D01*
G01X51618Y151700D01*
X54374D01*
Y103437D01*
X56188Y101624D01*
X56174Y101524D01*
G03X59122Y98576I2575J-373D01*
G01X59222Y98590D01*
X80024Y77788D01*
Y77269D01*
X79958Y77209D01*
G03X82457Y73406I1542J-1709D01*
G02X83024Y73043I167J-364D01*
G01Y68641D01*
X85959Y65706D01*
X85954Y65618D01*
G03X88135Y67799I2299J-118D01*
G01X88047Y67794D01*
X85976Y69865D01*
Y80612D01*
X80961Y85627D01*
X80975Y85727D01*
G03X77947Y88662I-2575J373D01*
G01X77844Y88644D01*
X59078Y107411D01*
Y184577D01*
X59900Y185400D01*
X62223D01*
G02X62545Y184763I0J-400D01*
G03X66109Y181858I1856J-1362D01*
G01X66169Y181924D01*
X70984D01*
X77999Y174909D01*
X77857Y174767D01*
G03X79038Y168198I2852J-2878D01*
G02X79155Y167551I-166J-364D01*
G01X73824Y162219D01*
Y157069D01*
X73758Y157009D01*
G03X76842I1542J-1709D01*
G01X76776Y157069D01*
Y159179D01*
G02X77494Y159423I400J1D01*
G03X82218Y165649I3215J2466D01*
G02X82085Y166303I150J371D01*
G01X82569Y166788D01*
X82823D01*
X85876Y169841D01*
Y170095D01*
X86295Y170513D01*
G02X86949Y170380I283J-283D01*
G03X94693Y172627I3760J1510D01*
G02X95086Y173100I393J73D01*
G01X96332D01*
G02X96725Y172627I0J-400D01*
G03X104693I3984J-738D01*
G02X105086Y173100I393J73D01*
G01X106332D01*
G02X106725Y172627I0J-400D01*
G03X114036Y174203I3984J-738D01*
G01X113940Y174340D01*
X114124Y174524D01*
X115912D01*
X144321Y202932D01*
X145830D01*
X145882Y202811D01*
G03X153633Y204856I3724J1598D01*
G02X154031Y205300I398J44D01*
G01X155181D01*
G02X155579Y204856I0J-400D01*
G03X162649Y207084I4027J-447D01*
G01X162525Y207225D01*
X166790Y211490D01*
X166931Y211366D01*
G03X168690Y218356I2675J3043D01*
G02X168200Y218746I-90J390D01*
G01Y220072D01*
G02X168690Y220462I400J0D01*
G03Y228356I916J3947D01*
G02X168200Y228746I-90J390D01*
G01Y230072D01*
G02X168690Y230462I400J0D01*
G03X173369Y235913I916J3947D01*
G01X173320Y236035D01*
X175308Y238024D01*
X176526D01*
G02X176803Y237335I0J-400D01*
G03X182409I2803J-2926D01*
G02X182686Y238024I277J289D01*
G01X182812D01*
X199752Y254964D01*
Y407741D01*
X203009Y410998D01*
G02X203692Y410715I283J-283D01*
G37*
G36*
G01X27802Y361252D02*
Y365600D01*
X22822Y370579D01*
Y449124D01*
G02X23505Y449407I400J0D01*
G01X30998Y441913D01*
Y362257D01*
X30824Y362234D01*
G03X28504Y360990I475J-3671D01*
G02X27802Y361252I-302J262D01*
G37*
G36*
G01X33900Y443188D02*
X27858Y449230D01*
G02X28223Y449904I283J282D01*
G03X37409Y454444I1698J8127D01*
G02X38170Y454271I361J-172D01*
G01Y447458D01*
X33900Y443188D01*
G37*
G36*
G01X38170Y461791D02*
G02X37409Y461618I-400J-1D01*
G03X26799Y465724I-7488J-3587D01*
G02X26366Y466378I-151J371D01*
G01X34276Y474288D01*
Y482944D01*
G02X34959Y483227I400J0D01*
G01X38170Y480016D01*
Y461791D01*
G37*
G36*
G01X26237Y529351D02*
X22822Y532766D01*
Y539091D01*
G02X23530Y539346I400J0D01*
G03X32601Y536788I6391J5300D01*
G02X33013Y536127I129J-378D01*
G01X26237Y529351D01*
G37*
G36*
G01X37055Y548893D02*
G03X23530Y549946I-7134J-4247D01*
G02X22822Y550201I-308J255D01*
G01Y557734D01*
X32976Y567888D01*
Y571599D01*
G02X33387Y571999I400J0D01*
G03X34853Y576125I63J2301D01*
G02X34813Y576725I243J318D01*
G01X37116Y579028D01*
G02X37799Y578745I283J-283D01*
G01X37798Y549098D01*
G02X37055Y548893I-400J0D01*
G37*
G36*
G01X12740Y568869D02*
G02X12058Y569152I-282J283D01*
G01Y621375D01*
G02X12806Y621572I400J0D01*
G03X44108Y626247I14753J8349D01*
G02X44898Y626160I390J-87D01*
G01Y598305D01*
X38622Y592029D01*
X38517Y592050D01*
G03X35551Y588620I-517J-2550D01*
G01X35594Y588501D01*
X25907Y578813D01*
G02X25302Y578858I-283J283D01*
G03X21151Y577373I-1852J-1367D01*
G01X21156Y577285D01*
X18508Y574637D01*
X18408Y574651D01*
G03X15460Y571703I-373J-2575D01*
G01X15474Y571603D01*
X12740Y568869D01*
G37*
G36*
G01X44108Y633595D02*
G03X12806Y638270I-16549J-3674D01*
G02X12058Y638467I-348J197D01*
G01Y658545D01*
X44216Y690704D01*
G02X44899Y690421I283J-283D01*
G01X44898Y677735D01*
G02X44336Y677369I-400J0D01*
G03X41434Y676824I-1056J-2378D01*
G02X40877Y676814I-284J282D01*
G03X40943Y673084I-1781J-1897D01*
G02X41500Y673094I284J-282D01*
G03X44336Y672613I1781J1897D01*
G02X44898Y672247I162J-366D01*
G01Y633682D01*
G02X44108Y633595I-400J0D01*
G37*
G36*
G01X34541Y1378047D02*
X22822Y1389766D01*
Y1418303D01*
G02X23530Y1418558I400J0D01*
G03X36312I6391J5300D01*
G02X37020Y1418303I308J-255D01*
G01Y1412508D01*
X35224Y1410712D01*
Y1378330D01*
G02X34541Y1378047I-400J0D01*
G37*
G36*
G01X11422Y1455571D02*
Y1488409D01*
X11993Y1488980D01*
X12227Y1488746D01*
X12179Y1488624D01*
G03X19041Y1484678I3727J-1459D01*
G02X19754Y1484429I313J-249D01*
G01Y1479901D01*
G02X19041Y1479652I-400J0D01*
G03Y1474678I-3135J-2487D01*
G02X19754Y1474429I313J-249D01*
G01Y1469901D01*
G02X19041Y1469652I-400J0D01*
G03X17372Y1463441I-3135J-2487D01*
G01X17494Y1463489D01*
X18004Y1462978D01*
Y1461226D01*
G02X17450Y1460857I-400J0D01*
G03X12102Y1455922I-1544J-3692D01*
G01X12140Y1455805D01*
X11764Y1455429D01*
G02X11422Y1455571I-142J141D01*
G37*
G36*
G01X94224Y241276D02*
G02X93908Y241922I0J400D01*
G03X86949Y245918I-3198J2487D01*
G02X86295Y245785I-371J150D01*
G01X85810Y246269D01*
Y246523D01*
X82823Y249510D01*
X78595D01*
X78586Y249502D01*
X73298D01*
X72840Y249960D01*
X72860Y250064D01*
G03X72349Y251996I-2260J436D01*
G01X72302Y252052D01*
Y266812D01*
X70033Y269081D01*
X70019Y269106D01*
G03X67807Y270294I-2019J-1106D01*
G01X67714Y270286D01*
X62586Y275414D01*
X62594Y275507D01*
G03X61842Y277409I-2294J193D01*
G01X61776Y277468D01*
Y288912D01*
X56026Y294662D01*
Y368387D01*
X54226Y370187D01*
Y432938D01*
X59906Y438618D01*
X59950Y438633D01*
G03X59450Y443673I-846J2461D01*
G01X59276Y443696D01*
Y478288D01*
X68276Y487288D01*
Y537088D01*
X74916Y543728D01*
G02X75599Y543445I283J-283D01*
G01X75598Y540973D01*
X75590Y540946D01*
G03Y539654I2210J-646D01*
G01X75598Y539627D01*
Y531315D01*
X75640Y531273D01*
Y530693D01*
X72798Y527851D01*
Y524787D01*
G02X72359Y524389I-400J0D01*
G03Y519211I-259J-2589D01*
G02X72798Y518813I39J-398D01*
G01Y517775D01*
G02X72345Y517379I-400J0D01*
G03Y512221I-345J-2579D01*
G02X72798Y511825I53J-396D01*
G01Y509842D01*
G02X72319Y509450I-400J0D01*
G03Y504350I-519J-2550D01*
G02X72798Y503958I79J-392D01*
G01Y503514D01*
X72573D01*
X72549Y503520D01*
G03X72332Y498434I-649J-2520D01*
G02X72798Y498040I66J-394D01*
G01Y447356D01*
X62521Y437078D01*
X62467Y437065D01*
G03X65388Y433308I629J-2525D01*
G02X66108Y433276I352J-189D01*
G03X69279Y436783I2392J1024D01*
G02X69116Y437447I120J381D01*
G01X77202Y445532D01*
Y478758D01*
G02X77681Y479150I400J0D01*
G03X80669Y480879I519J2550D01*
G02X81175Y481132I379J-126D01*
G03X84230Y484941I825J2468D01*
G01X84202Y484988D01*
Y489536D01*
X95202Y500536D01*
Y527411D01*
X93334Y529278D01*
X93320Y529304D01*
G03X89671Y529827I-2020J-1104D01*
G02X89138Y529797I-283J282D01*
G03X85490Y527354I-1438J-1797D01*
G01X85498Y527327D01*
Y526361D01*
X87598Y524261D01*
Y508444D01*
G02X86906Y508172I-400J1D01*
G03Y504628I-1906J-1772D01*
G02X87598Y504356I292J-273D01*
G01Y503686D01*
X77884Y493972D01*
G02X77201Y494255I-283J283D01*
G01X77202Y498058D01*
G02X77681Y498450I400J0D01*
G03Y503550I519J2550D01*
G02X77202Y503942I-79J392D01*
G01Y504322D01*
X77442D01*
X77480Y504306D01*
G03X77721Y509183I1020J2394D01*
G02X77202Y509564I-119J381D01*
G01Y511825D01*
G02X77655Y512221I400J0D01*
G03Y517379I345J2579D01*
G02X77202Y517775I-53J396D01*
G01Y519396D01*
G02X77841Y519717I400J0D01*
G03Y523883I1559J2083D01*
G02X77202Y524204I-239J321D01*
G01Y526027D01*
X80044Y528869D01*
Y533097D01*
X80002Y533139D01*
Y539627D01*
X80010Y539654D01*
G03Y540946I-2210J646D01*
G01X80002Y540973D01*
Y542588D01*
X113413Y576000D01*
X119665D01*
G02X120055Y575511I0J-400D01*
G03X122482Y572705I2245J-511D01*
G01X122574Y572713D01*
X125698Y569588D01*
Y545779D01*
G02X125016Y545496I-400J0D01*
G01X117236Y553276D01*
X117068D01*
X117009Y553342D01*
G03X113038Y552229I-1709J-1542D01*
G02X112313Y552081I-393J74D01*
G03X108381Y551906I-1913J-1281D01*
G01X108367Y551881D01*
X103098Y546612D01*
Y526588D01*
X103070Y526541D01*
G03X102775Y525829I2230J-1341D01*
G01X102762Y525775D01*
X101324Y524337D01*
Y521956D01*
G02X100800Y521576I-400J0D01*
G03Y516624I-800J-2476D01*
G02X101324Y516244I124J-380D01*
G01Y514856D01*
G02X100800Y514476I-400J0D01*
G03Y509524I-800J-2476D01*
G02X101324Y509144I124J-380D01*
G01Y508856D01*
G02X100800Y508476I-400J0D01*
G03Y503524I-800J-2476D01*
G02X101324Y503144I124J-380D01*
G01Y502856D01*
G02X100800Y502476I-400J0D01*
G03Y497524I-800J-2476D01*
G02X101324Y497144I124J-380D01*
G01Y496856D01*
G02X100800Y496476I-400J0D01*
G03Y491524I-800J-2476D01*
G02X101324Y491144I124J-380D01*
G01Y490856D01*
G02X100800Y490476I-400J0D01*
G03Y485524I-800J-2476D01*
G02X101324Y485144I124J-380D01*
G01Y484784D01*
G02X100774Y484413I-400J0D01*
G03Y479587I-974J-2413D01*
G02X101324Y479216I150J-371D01*
G01Y475643D01*
G02X100734Y475291I-400J0D01*
G03Y470709I-1234J-2291D01*
G02X101324Y470357I190J-352D01*
G01Y453963D01*
X116488Y438798D01*
X116702D01*
G02X116844Y438457I0J-200D01*
G01X110588Y432202D01*
X87475D01*
G02X87079Y432655I0J400D01*
G03X81921I-2579J345D01*
G02X81525Y432202I-396J-53D01*
G01X77588D01*
X76919Y431533D01*
X76894Y431519D01*
G03X79496Y427751I1105J-2019D01*
G01X79552Y427798D01*
X85636D01*
G02X86017Y427279I0J-400D01*
G03X90983I2483J-779D01*
G02X91364Y427798I381J119D01*
G01X112412D01*
X123581Y438967D01*
X123606Y438981D01*
G03X121854Y443210I-1105J2020D01*
G01X121827Y443202D01*
X118312D01*
X105726Y455787D01*
Y522513D01*
X105875Y522662D01*
X105929Y522675D01*
G03X107530Y526541I-629J2525D01*
G01X107502Y526588D01*
Y544788D01*
X111481Y548767D01*
X111506Y548781D01*
G03X112662Y550371I-1106J2019D01*
G02X113387Y550519I393J-74D01*
G03X116373Y549764I1912J1281D01*
G01X116504Y549832D01*
X144698Y521637D01*
Y520487D01*
G02X144259Y520089I-400J0D01*
G03Y514911I-259J-2589D01*
G02X144698Y514513I39J-398D01*
G01Y512185D01*
G02X144254Y511788I-400J0D01*
G03Y507212I-254J-2288D01*
G02X144698Y506815I44J-397D01*
G01Y504487D01*
G02X144259Y504089I-400J0D01*
G03Y498911I-259J-2589D01*
G02X144698Y498513I39J-398D01*
G01Y496487D01*
G02X144259Y496089I-400J0D01*
G03Y490911I-259J-2589D01*
G02X144698Y490513I39J-398D01*
G01Y489169D01*
G02X144259Y488771I-400J0D01*
G03Y483593I-259J-2589D01*
G02X144698Y483195I39J-398D01*
G01Y454711D01*
X138606Y448618D01*
G02X138014Y448648I-282J283D01*
G03X133833Y448440I-2014J-1648D01*
G02X133167I-333J222D01*
G03Y445560I-2167J-1440D01*
G02X133833I333J-222D01*
G03X133996Y445341I2166J1442D01*
G01X134112Y445201D01*
X125724Y436813D01*
Y247768D01*
X125658Y247709D01*
G03X128742I1542J-1709D01*
G01X128676Y247768D01*
Y429144D01*
G02X129200Y429524I400J0D01*
G03Y434476I800J2476D01*
G02X128676Y434856I-124J380D01*
G01Y435589D01*
X132931Y439843D01*
G02X133552Y439774I283J-283D01*
G03X135524Y438698I1948J1226D01*
G01Y426988D01*
X139924Y422588D01*
Y384212D01*
X134324Y378612D01*
Y246812D01*
X130788Y243276D01*
X120612D01*
X113312Y250576D01*
X104788D01*
X102335Y248123D01*
X102212Y248172D01*
G03X97510Y241922I-1503J-3763D01*
G02X97194Y241276I-316J-246D01*
G01X94224D01*
G37*
G36*
G01X41476Y522569D02*
X53441Y534534D01*
G02X54124Y534251I283J-283D01*
G01Y524717D01*
G02X53454Y524422I-400J0D01*
G03Y520578I-1754J-1922D01*
G02X54124Y520283I270J-295D01*
G01Y515260D01*
G02X53483Y514940I-400J0D01*
G03Y511260I-1383J-1840D01*
G02X54124Y510940I241J-320D01*
G01Y504813D01*
G02X53371Y504624I-400J0D01*
G03X42168Y506089I-6127J-3286D01*
G02X41476Y506363I-292J274D01*
G01Y522569D01*
G37*
G36*
G01X62327Y545180D02*
X62326Y553938D01*
X83576Y575188D01*
Y582836D01*
X88716Y587976D01*
G02X89398Y587693I282J-283D01*
G01Y581687D01*
X85524Y577812D01*
Y567412D01*
X63009Y544897D01*
G02X62327Y545180I-282J283D01*
G37*
G36*
G01X60577Y557330D02*
X60576Y559812D01*
X73452Y572687D01*
Y574011D01*
X79941Y580501D01*
G02X80624Y580218I283J-283D01*
G01Y576412D01*
X61259Y557047D01*
G02X60577Y557330I-282J283D01*
G37*
G36*
G01X67876Y572254D02*
Y575688D01*
X78141Y585953D01*
G02X78824Y585670I283J-283D01*
G01Y583560D01*
X70498Y575235D01*
Y573911D01*
X68559Y571971D01*
G02X67876Y572254I-283J283D01*
G37*
G36*
G01X48326Y565880D02*
Y574538D01*
X54641Y580853D01*
G02X55324Y580570I283J-283D01*
G01Y579095D01*
X55243Y579035D01*
G03X56795Y574348I1557J-2085D01*
G02X57077Y573665I-1J-400D01*
G01X49009Y565597D01*
G02X48326Y565880I-283J283D01*
G37*
G36*
G01X55202Y593073D02*
Y672827D01*
X55210Y672854D01*
G03Y674146I-2210J646D01*
G01X55202Y674173D01*
Y676447D01*
X56622Y677868D01*
X56705D01*
G03X58411Y678357I5J3201D01*
G02X59024Y678018I213J-339D01*
G01Y676845D01*
X58943Y676785D01*
G03Y672615I1557J-2085D01*
G01X59024Y672555D01*
Y671535D01*
X58989Y671484D01*
G03X62074Y672180I1911J-1284D01*
G01X61976Y672238D01*
Y672555D01*
X62057Y672615D01*
G03Y676785I-1557J2085D01*
G01X61976Y676845D01*
Y679407D01*
G02X62659Y679689I400J-1D01*
G01X65824Y676525D01*
Y664070D01*
X67003Y662890D01*
X67000Y662803D01*
G03X67834Y660789I2600J-103D01*
G01X67898Y660729D01*
Y619205D01*
X62298Y613605D01*
Y599205D01*
X55884Y592791D01*
G02X55202Y593073I-282J283D01*
G37*
G36*
G01X91372Y670288D02*
X97901Y663760D01*
X97908Y663688D01*
G03X100561Y661626I2292J212D01*
G02X101024Y661231I63J-395D01*
G01Y659602D01*
G02X100620Y659202I-400J0D01*
G03X99043Y654515I-20J-2602D01*
G01X99124Y654455D01*
Y644712D01*
X73934Y619522D01*
G02X73251Y619805I-283J283D01*
G01Y664117D01*
G02X73934Y664400I400J0D01*
G01X80061Y658272D01*
X81755D01*
X81815Y658192D01*
G03X85985I2085J1557D01*
G01X86045Y658272D01*
X86822D01*
X86882Y658192D01*
G03X91462Y660489I2085J1557D01*
G02X91689Y660971I383J114D01*
G03X92231Y665452I-1015J2396D01*
G01X92150Y665512D01*
Y666338D01*
X86071Y672417D01*
X86163Y672553D01*
G03X85636Y676023I-2163J1447D01*
G02X85586Y676597I251J311D01*
G03X86138Y678358I-1736J1511D01*
G02X86545Y678802I398J44D01*
G03X86715Y678804I58J2301D01*
G01X86803Y678809D01*
X91372Y674239D01*
Y670288D01*
G37*
G36*
G01X73425Y725737D02*
X73483Y725749D01*
G03X73643Y725790I-491J2249D01*
G01X73670Y725797D01*
X73898D01*
Y700515D01*
X69084Y695700D01*
G02X68401Y695983I-283J283D01*
G01X68402Y720713D01*
X73425Y725737D01*
G37*
G36*
G01X52484Y679957D02*
G02X51801Y680240I-283J283D01*
G01X51802Y703287D01*
X51794Y703294D01*
X51799Y703382D01*
G03X49173Y705779I-2299J118D01*
G02X48729Y706075I-57J396D01*
G03X44797Y707049I-2229J-575D01*
G02X44102Y707318I-295J270D01*
G01Y752305D01*
X41496Y754911D01*
Y756136D01*
G02X42186Y756410I400J-1D01*
G03X52875Y757103I5058J4771D01*
G02X53598Y756868I323J-235D01*
G01Y697197D01*
X54482Y696313D01*
X54483Y693210D01*
X53508Y692236D01*
Y681069D01*
G03X53509Y681064I3079J613D01*
G01Y680981D01*
X52484Y679957D01*
G37*
G36*
G01X73425Y730262D02*
G03X70876Y728888I-425J-2262D01*
G02X70284Y728711I-369J155D01*
G03X67721Y724886I-1284J-1911D01*
G02X67782Y724270I-222J-333D01*
G01X66884Y723372D01*
G02X66201Y723655I-283J283D01*
G01Y759595D01*
G02X66884Y759878I400J0D01*
G01X73898Y752863D01*
Y730656D01*
G02X73425Y730262I-400J-1D01*
G37*
G36*
G01X127124Y665430D02*
G02X126441Y665147I-400J0D01*
G01X125152Y666437D01*
Y688486D01*
X123263Y690374D01*
X123277Y690474D01*
G03X118352Y689729I-2575J373D01*
G02X118202Y689218I-361J-172D01*
G03X117001Y686635I1374J-2210D01*
G01X117015Y686535D01*
X115348Y684869D01*
Y668749D01*
G02X115007Y668608I-200J0D01*
G01X114676Y668939D01*
Y699712D01*
X113102Y701287D01*
Y761313D01*
X114744Y762956D01*
X114844Y762942D01*
G03X117792Y765890I373J2575D01*
G01X117778Y765990D01*
X128152Y776363D01*
Y852189D01*
X114789Y865552D01*
X108342D01*
X107370Y864579D01*
X107282Y864584D01*
G03X105455Y863827I-118J-2299D01*
G01X105396Y863762D01*
X104585D01*
X104551Y863920D01*
G03X100597Y864987I-2251J-482D01*
G02X99902Y865256I-295J270D01*
G01Y870513D01*
X101294Y871906D01*
X101382Y871901D01*
G03X99201Y874082I118J2299D01*
G01X99206Y873994D01*
X96948Y871737D01*
Y834863D01*
X97424Y834388D01*
Y824668D01*
X97358Y824609D01*
G03X100442I1542J-1709D01*
G01X100376Y824668D01*
Y835612D01*
X99902Y836087D01*
Y838298D01*
G02X100301Y838698I400J0D01*
G03X102009Y839458I-1J2302D01*
G01X102068Y839524D01*
X104422D01*
X104482Y839434D01*
G03X107721Y838812I1922J1266D01*
G01X107858Y838908D01*
X115398Y831367D01*
Y826800D01*
G02X114984Y826400I-400J0D01*
G03X112639Y823669I-84J-2300D01*
G01X112659Y823565D01*
X105953Y816860D01*
X105866Y816863D01*
G03X103163Y814160I-103J-2600D01*
G01X103166Y814073D01*
X84798Y795705D01*
Y756680D01*
G02X84116Y756397I-400J0D01*
G01X73876Y766637D01*
Y821132D01*
X73942Y821191D01*
G03X74008Y824547I-1542J1709D01*
G02X74004Y825116I279J286D01*
G01X74152Y825263D01*
Y1128729D01*
X69863Y1133017D01*
X69877Y1133117D01*
G03X67675Y1130915I-2575J373D01*
G01X67775Y1130929D01*
X71198Y1127505D01*
Y906155D01*
G02X70516Y905872I-400J0D01*
G01X69561Y906827D01*
X69575Y906927D01*
G03X68557Y909385I-2575J373D01*
G01X68476Y909445D01*
Y1013764D01*
X55278Y1026962D01*
X55273Y1026969D01*
G03X54467Y1023411I-1773J-1469D01*
G01X54594Y1023470D01*
X65524Y1012540D01*
Y983284D01*
G02X64974Y982913I-400J0D01*
G03Y978087I-974J-2413D01*
G02X65524Y977716I150J-371D01*
G01Y918430D01*
G02X64841Y918147I-400J0D01*
G01X56761Y926227D01*
X56775Y926327D01*
G03X54642Y929264I-2575J373D01*
G01X54476Y929293D01*
Y994243D01*
X54622Y994284D01*
G03X53256Y998678I-622J2216D01*
G02X52726Y999057I-130J379D01*
G01Y1016476D01*
X52773Y1016531D01*
G03X50916Y1020300I-1773J1469D01*
G02X50502Y1020700I-14J400D01*
G01Y1121195D01*
X56737Y1127430D01*
X56824Y1127427D01*
G03X59527Y1130130I103J2600D01*
G01X59524Y1130217D01*
X72208Y1142901D01*
G02X72890Y1142619I282J-283D01*
G01Y1142021D01*
X79024Y1135888D01*
Y1124388D01*
X121424Y1081988D01*
Y1009545D01*
X121343Y1009485D01*
G03Y1005315I1557J-2085D01*
G01X121424Y1005255D01*
Y1004948D01*
X139648Y986723D01*
Y951643D01*
X141611Y949680D01*
X145239D01*
X146294Y950736D01*
X146382Y950731D01*
G03X148533Y951950I118J2299D01*
G02X148794Y952037I176J-94D01*
G03X150323Y951886I978J2084D01*
G02X150560Y951754I47J-194D01*
G03X151054Y950914I2187J721D01*
G01X151185Y950773D01*
X146148Y945737D01*
Y902366D01*
X146073Y902306D01*
G03X147499Y898198I1427J-1806D01*
G02X147898Y897798I-1J-400D01*
G01Y847487D01*
X132098Y831687D01*
Y683507D01*
X127124Y678532D01*
Y671645D01*
X127043Y671585D01*
G03Y667415I1557J-2085D01*
G01X127124Y667355D01*
Y665430D01*
G37*
G36*
G01X66202Y828555D02*
Y843887D01*
X59540Y850548D01*
X59677Y850689D01*
G03X59366Y854585I-1868J1811D01*
G01X59286Y854645D01*
Y881251D01*
X57476Y883060D01*
Y883732D01*
X57542Y883791D01*
G03X53729Y885124I-1542J1709D01*
G02X53051Y884776I-395J-65D01*
G01X52802Y885026D01*
X52801Y902227D01*
G02X53484Y902509I400J-1D01*
G01X59198Y896795D01*
Y894971D01*
X59134Y894911D01*
G03X59784Y890649I1766J-1911D01*
G01X59898Y890595D01*
Y886752D01*
X59851Y886696D01*
G03X61859Y882913I1749J-1496D01*
G02X62303Y882543I45J-397D01*
G03X66349Y884196I2297J157D01*
G01X66302Y884252D01*
Y886144D01*
G02X66775Y886538I400J1D01*
G03X67284Y886500I425J2262D01*
G02X67698Y886100I14J-400D01*
G01Y829087D01*
X66884Y828272D01*
G02X66202Y828555I-282J283D01*
G37*
G36*
G01X56116Y908291D02*
X50502Y913905D01*
Y921127D01*
G02X51184Y921409I400J-1D01*
G01X56798Y915795D01*
Y914471D01*
X56734Y914411D01*
G03Y910589I1766J-1911D01*
G01X56798Y910529D01*
Y908573D01*
G02X56116Y908291I-400J1D01*
G37*
G36*
G01X78765Y1145480D02*
X83024Y1141221D01*
Y1140110D01*
G02X82341Y1139827I-400J0D01*
G01X77594Y1144575D01*
Y1145054D01*
G02X78033Y1145452I400J0D01*
G03X78665Y1145466I259J2589D01*
G01X78765Y1145480D01*
G37*
G36*
G01X64702Y1144573D02*
Y1161374D01*
X66016Y1162688D01*
G02X66698Y1162405I282J-283D01*
G01Y1145605D01*
X65384Y1144291D01*
G02X64702Y1144573I-282J283D01*
G37*
G36*
G01X40041Y1375047D02*
X38176Y1376912D01*
Y1409488D01*
X39800Y1411112D01*
X40724Y1410188D01*
Y1375330D01*
G02X40041Y1375047I-400J0D01*
G37*
G36*
G01X127513Y576000D02*
X129981Y578467D01*
X130006Y578481D01*
G03X126881Y581606I-1106J2019D01*
G01X126867Y581581D01*
X125689Y580403D01*
X112556D01*
G02X112273Y581085I0J400D01*
G01X126687Y595499D01*
G02X127271Y595481I284J-282D01*
G03X130709Y595458I1729J1519D01*
G01X130768Y595524D01*
X134355D01*
X134415Y595443D01*
G03X138585I2085J1557D01*
G01X138645Y595524D01*
X145212D01*
X148862Y599174D01*
X155162D01*
X171826Y615837D01*
Y617804D01*
X171906Y617864D01*
G03X168792I-1557J2085D01*
G01X168872Y617804D01*
Y617061D01*
X153938Y602126D01*
X149756D01*
G02X149473Y602809I0J400D01*
G01X160200Y613536D01*
Y625925D01*
X154826Y631299D01*
Y660435D01*
X153993Y661268D01*
X154007Y661368D01*
G03X152989Y663826I-2575J373D01*
G01X152908Y663886D01*
Y666657D01*
X161002Y674750D01*
Y683487D01*
X160926Y683562D01*
Y688320D01*
G02X161609Y688603I400J0D01*
G01X168324Y681888D01*
Y627188D01*
X176498Y619013D01*
Y615887D01*
X150213Y589601D01*
G02X149629Y589619I-284J282D01*
G03X146081Y586689I-1729J-1519D01*
G01X146124Y586634D01*
Y556488D01*
X149724Y552888D01*
Y526477D01*
G02X149041Y526194I-400J0D01*
G01X134533Y540702D01*
X134519Y540727D01*
G03X133606Y541640I-2019J-1106D01*
G01X133581Y541654D01*
X130102Y545133D01*
Y571412D01*
X126197Y575317D01*
G02X126480Y576000I283J283D01*
G01X127513D01*
G37*
G36*
G01X81776Y586178D02*
Y587088D01*
X85576Y590888D01*
Y592070D01*
G02X86259Y592353I400J0D01*
G01X87398Y591213D01*
Y590835D01*
X82459Y585895D01*
G02X81776Y586178I-283J283D01*
G37*
G36*
G01X88476Y566076D02*
Y576588D01*
X92352Y580463D01*
Y596389D01*
X89932Y598809D01*
Y599033D01*
G02X90371Y599431I400J0D01*
G03X91003Y599445I259J2589D01*
G01X91103Y599459D01*
X97013Y593548D01*
X116595D01*
G02X116924Y592921I0J-400D01*
G01Y592812D01*
X90188Y566076D01*
X88476D01*
G37*
G36*
G01X145559Y604698D02*
X156565Y615705D01*
G02X157247Y615422I282J-283D01*
G01X157248Y614760D01*
X143414Y600926D01*
X130180D01*
G02X129897Y601609I0J400D01*
G01X132987Y604698D01*
X145559D01*
G37*
G36*
G01X102759Y645747D02*
G02X102077Y646030I-282J283D01*
G01X102076Y654455D01*
X102157Y654515D01*
G03X103175Y656973I-1557J2085D01*
G01X103161Y657073D01*
X103976Y657888D01*
Y669312D01*
X103161Y670127D01*
X103175Y670227D01*
G03X100620Y667998I-2575J373D01*
G02X101024Y667598I4J-400D01*
G01Y666569D01*
G02X100561Y666174I-400J0D01*
G03X99793Y666166I-360J-2274D01*
G01X99690Y666147D01*
X94326Y671512D01*
Y675463D01*
X88891Y680897D01*
X88896Y680985D01*
G03X88139Y682812I-2299J118D01*
G01X88074Y682871D01*
Y688907D01*
X84402Y692579D01*
Y721399D01*
G02X85053Y721710I400J0D01*
G03X88249Y724996I1446J1791D01*
G01X88202Y725052D01*
Y794295D01*
X105573Y811666D01*
X105660Y811663D01*
G03X108363Y814366I103J2600D01*
G01X108360Y814453D01*
X108941Y815034D01*
G02X109624Y814752I283J-283D01*
G01Y804417D01*
G02X108927Y804148I-400J0D01*
G03X105141Y800580I-1927J-1748D01*
G02Y800020I-286J-280D01*
G03X105010Y796524I1859J-1820D01*
G02X104994Y795991I-306J-258D01*
G03X108912Y792573I1888J-1791D01*
G02X109624Y792322I312J-251D01*
G01Y790345D01*
X109543Y790285D01*
G03Y786115I1557J-2085D01*
G01X109624Y786055D01*
Y783812D01*
X106398Y780587D01*
Y737712D01*
X106396Y737710D01*
Y709167D01*
X106398Y709165D01*
Y708835D01*
X106396Y708833D01*
Y698588D01*
X104846Y697038D01*
Y678565D01*
X107812Y675600D01*
Y673711D01*
X107810Y673710D01*
Y667861D01*
X107722Y667801D01*
G03X110546Y664180I1282J-1912D01*
G02X111096Y664165I267J-297D01*
G01X111706Y663556D01*
X111701Y663468D01*
G03X114118Y661051I2299J-118D01*
G01X114206Y661056D01*
X115987Y659274D01*
X117439D01*
X120871Y655843D01*
G02Y655277I-283J-283D01*
G03X120201Y653532I1629J-1627D01*
G01X120206Y653444D01*
X119883Y653121D01*
X119693Y653312D01*
X119685Y653380D01*
G03X115721Y654675I-2285J-280D01*
G02X115079Y654756I-292J274D01*
G03X111408Y655699I-2279J-1256D01*
G02X110796Y656008I-213J338D01*
G03X106643Y653740I-2596J-183D01*
G01X106724Y653680D01*
Y651301D01*
G02X106334Y650901I-400J0D01*
G03X104037Y647210I66J-2601D01*
G01X104096Y647084D01*
X102759Y645747D01*
G37*
G36*
G01X119341Y667247D02*
X118302Y668287D01*
Y683645D01*
X118711Y684055D01*
X118920Y683847D01*
X118910Y683753D01*
G03X119943Y681415I2590J-253D01*
G01X120024Y681355D01*
Y667530D01*
G02X119341Y667247I-400J0D01*
G37*
G36*
G01X109241Y678347D02*
X107800Y679789D01*
Y695814D01*
X109350Y697364D01*
Y697880D01*
G02X109691Y698021I200J0D01*
G01X109924Y697788D01*
Y678630D01*
G02X109241Y678347I-400J0D01*
G37*
G36*
G01X125198Y777587D02*
X115690Y768078D01*
X115590Y768092D01*
G03X112642Y765144I-373J-2575D01*
G01X112656Y765044D01*
X112034Y764422D01*
G02X111351Y764705I-283J283D01*
G01X111352Y772263D01*
X115929Y776841D01*
X116029Y776827D01*
G03X118977Y779775I373J2575D01*
G01X118963Y779875D01*
X120102Y781013D01*
Y836687D01*
X112976Y843812D01*
Y849832D01*
X113042Y849891D01*
G03Y853309I-1542J1709D01*
G01X112976Y853368D01*
Y859688D01*
X113194Y859906D01*
X113282Y859901D01*
G03X115027Y860571I118J2299D01*
G02X115593I283J-283D01*
G01X125198Y850965D01*
Y777587D01*
G37*
G36*
G01X117148Y782237D02*
X116875Y781963D01*
X116775Y781977D01*
G03X113827Y779029I-373J-2575D01*
G01X113841Y778929D01*
X110034Y775122D01*
G02X109351Y775405I-283J283D01*
G01X109352Y779363D01*
X112576Y782588D01*
Y786055D01*
X112657Y786115D01*
G03Y790285I-1557J2085D01*
G01X112576Y790345D01*
Y816188D01*
X116466Y820078D01*
G02X117148Y819795I282J-283D01*
G01Y782237D01*
G37*
G36*
G01X140188Y241000D02*
X139912Y241276D01*
X139270D01*
G02X138870Y241677I0J400D01*
G03X138753Y241959I-400J-1D01*
G01X136200Y244512D01*
X137276Y245588D01*
Y377388D01*
X142876Y382988D01*
Y423812D01*
X138476Y428212D01*
Y437188D01*
X152676Y451388D01*
Y554112D01*
X149076Y557712D01*
Y561169D01*
G02X149759Y561452I400J0D01*
G01X166527Y544684D01*
G02X166244Y544002I-283J-282D01*
G01X160523D01*
X160496Y544010D01*
G03Y539590I-646J-2210D01*
G01X160523Y539598D01*
X166588D01*
X176762Y529425D01*
X176775Y529371D01*
G03X177186Y528483I2525J629D01*
G01X177224Y528431D01*
Y525605D01*
G02X176567Y525298I-400J0D01*
G03Y521302I-1667J-1998D01*
G02X177224Y520995I257J-307D01*
G01Y449413D01*
X188752Y437884D01*
G02X188469Y437201I-283J-283D01*
G01X148648D01*
X145879Y434433D01*
X145854Y434419D01*
G03X144898Y433423I1106J-2019D01*
G02X144201Y433388I-358J178D01*
G03X144395Y430983I-2201J-1388D01*
G02X145088Y431060I368J-156D01*
G03X148979Y431294I1872J1340D01*
G01X148993Y431319D01*
X150472Y432798D01*
X159025D01*
G02X159421Y432345I0J-400D01*
G03X164579I2579J-345D01*
G02X164975Y432798I396J53D01*
G01X171525D01*
G02X171921Y432345I0J-400D01*
G03X177079I2579J-345D01*
G02X177475Y432798I396J53D01*
G01X188420D01*
X188898Y432320D01*
Y431793D01*
X189367Y431324D01*
X189381Y431299D01*
G03X192357Y430311I2019J1106D01*
G02X192924Y429948I167J-364D01*
G01Y426712D01*
X188324Y422112D01*
Y390488D01*
X190824Y387988D01*
Y274312D01*
X184214Y267702D01*
G02X183542Y267890I-283J283D01*
G03X176418Y264427I-3936J-961D01*
G02X176104Y263780I-315J-247D01*
G01X173108D01*
G02X172794Y264427I1J400D01*
G03X167377Y263545I-3188J2502D01*
G02X167440Y262928I-220J-334D01*
G01X163607Y259095D01*
G02X162990Y259158I-283J283D01*
G03X161715Y253469I-3384J-2229D01*
G02X162324Y253128I209J-341D01*
G01Y248210D01*
G02X161715Y247869I-400J0D01*
G03X156620Y241670I-2109J-3460D01*
G02X156325Y241000I-295J-270D01*
G01X152887D01*
G02X152592Y241670I0J400D01*
G03X146620I-2986J2739D01*
G02X146325Y241000I-295J-270D01*
G01X140188D01*
G37*
G36*
G01X179452Y617005D02*
Y620237D01*
X174427Y625261D01*
G02X174634Y625936I283J282D01*
G03X175397Y630160I-438J2260D01*
G01X175302Y630218D01*
Y691512D01*
X164702Y702112D01*
Y734312D01*
X160802Y738212D01*
Y751927D01*
X160810Y751954D01*
G03Y753246I-2210J646D01*
G01X160802Y753273D01*
Y825788D01*
X178876Y843863D01*
X178877Y986470D01*
G02X179559Y986753I400J0D01*
G01X182698Y983613D01*
Y950187D01*
X180848Y948337D01*
Y776513D01*
X166648Y762313D01*
Y729789D01*
X170824Y725614D01*
Y696988D01*
X179624Y688188D01*
Y643788D01*
X182324Y641088D01*
Y618912D01*
X180134Y616722D01*
G02X179452Y617005I-282J283D01*
G37*
G36*
G01X134814Y664274D02*
X134202Y664887D01*
Y669113D01*
X134814Y669726D01*
G02X135496Y669443I282J-283D01*
G01Y664557D01*
G02X134814Y664274I-400J0D01*
G37*
G36*
G01X132370Y672424D02*
Y675759D01*
X132538Y675786D01*
G03X134685Y678726I-428J2567D01*
G01X134671Y678826D01*
X135341Y679496D01*
G02X136024Y679213I283J-283D01*
G01Y675112D01*
X133053Y672141D01*
G02X132370Y672424I-283J283D01*
G37*
G36*
G01X147202Y673036D02*
Y685912D01*
X145196Y687918D01*
Y828087D01*
X146491Y829383D01*
G02X147174Y829100I283J-283D01*
G01Y733638D01*
X147402Y733409D01*
Y699491D01*
X147348Y699437D01*
Y689363D01*
X148688Y688024D01*
X148681Y687933D01*
G03X149456Y686048I2297J-158D01*
G01X149524Y685988D01*
Y674393D01*
X147884Y672753D01*
G02X147202Y673036I-282J283D01*
G37*
G36*
G01X170216Y684172D02*
X163612Y690776D01*
X163657Y690896D01*
G03X161565Y694001I-2157J804D01*
G02X161176Y694401I11J400D01*
G01Y698444D01*
G02X161859Y698727I400J0D01*
G01X170898Y689688D01*
Y684455D01*
G02X170216Y684172I-400J0D01*
G37*
G36*
G01X152802Y848355D02*
Y941290D01*
X156341Y944830D01*
G02X157024Y944547I283J-283D01*
G01Y900171D01*
X156902Y900119D01*
G03X158331Y895760I899J-2119D01*
G02X158824Y895371I93J-389D01*
G01Y853412D01*
X153484Y848072D01*
G02X152802Y848355I-282J283D01*
G37*
G36*
G01X162988Y986224D02*
X164324Y984888D01*
Y971230D01*
G02X163641Y970947I-400J0D01*
G01X162376Y972212D01*
Y985212D01*
X162047Y985541D01*
G02X162330Y986224I283J283D01*
G01X162988D01*
G37*
G36*
G01X143609Y1015703D02*
X164128Y995184D01*
G02X163845Y994502I-283J-282D01*
G01X162405D01*
X142926Y1013980D01*
X142927Y1015420D01*
G02X143609Y1015703I400J0D01*
G37*
G36*
G01X192616Y390372D02*
X191276Y391712D01*
Y420888D01*
X194416Y424028D01*
G02X195098Y423745I282J-283D01*
G01Y423287D01*
X193298Y421487D01*
Y390655D01*
G02X192616Y390372I-400J0D01*
G37*
G36*
G01X198002Y411132D02*
Y419513D01*
X199802Y421313D01*
Y437790D01*
X201016Y439005D01*
G02X201698Y438722I282J-283D01*
G01Y413864D01*
X198684Y410849D01*
G02X198002Y411132I-282J283D01*
G37*
G36*
G01X192506Y522195D02*
G03X189009Y525714I-2306J1205D01*
G02X188426Y526069I-183J356D01*
G01Y533396D01*
G02X189109Y533679I400J0D01*
G01X194848Y527939D01*
Y521980D01*
G02X194335Y521596I-400J-1D01*
G03X192959Y521622I-735J-2496D01*
G02X192506Y522195I-99J388D01*
G37*
%LPC*%
G75*
G36*
G01X152884Y1580957D02*
G02Y1583043I-2384J1043D01*
G03X153616I366J161D01*
G02Y1580957I2384J-1043D01*
G03X152884I-366J-161D01*
G37*
G36*
G01X129501Y1565053D02*
G02X127633Y1564714I-501J-2553D01*
G03X127499Y1565447I-210J340D01*
G02X129367Y1565786I501J2553D01*
G03X129501Y1565053I210J-340D01*
G37*
G36*
G01X156440Y1122167D02*
G02X153560I-1440J-2167D01*
G03Y1122833I-222J333D01*
G02X153957Y1127384I1440J2167D01*
G03Y1128116I-161J366D01*
G02X156043I1043J2384D01*
G03Y1127384I161J-366D01*
G02X156440Y1122833I-1043J-2384D01*
G03Y1122167I222J-333D01*
G37*
G36*
G01X94352Y108863D02*
G02X92415Y109226I-1352J-1863D01*
G03X92548Y109937I-102J387D01*
G02X94485Y109574I1352J1863D01*
G03X94352Y108863I102J-387D01*
G37*
G36*
G01X93048Y90796D02*
G03Y90204I269J-296D01*
G02X89952I-1548J-1704D01*
G03Y90796I-269J296D01*
G02X90038Y94278I1548J1704D01*
G03X89964Y94944I-254J309D01*
G02X92462Y95222I1036J2056D01*
G03X92536Y94556I254J-309D01*
G02X93048Y90796I-1036J-2056D01*
G37*
G36*
G01X102399Y1433476D02*
X102888D01*
X106939Y1437527D01*
X106925Y1437627D01*
G02X109127Y1435425I2575J373D01*
G01X109027Y1435439D01*
X104169Y1430581D01*
X104157Y1430520D01*
G02X101492Y1428400I-2557J480D01*
G03X101079Y1428054I-17J-400D01*
G02X98608Y1431000I-2579J346D01*
G03X99021Y1431346I17J400D01*
G02X102370Y1433485I2579J-346D01*
G01X102399Y1433476D01*
G37*
G36*
G01X176827Y1567298D02*
X174310D01*
X171118Y1564106D01*
G03X171147Y1563514I283J-283D01*
G02X167486Y1559853I-1647J-2014D01*
G03X166894Y1559882I-309J-254D01*
G01X159202Y1552190D01*
Y1545904D01*
G03X159841Y1545583I400J0D01*
G02Y1541417I1559J-2083D01*
G03X159202Y1541096I-239J-321D01*
G01Y1529388D01*
X159230Y1529341D01*
G02Y1526659I-2230J-1341D01*
G01X159202Y1526612D01*
Y1499088D01*
X155533Y1495419D01*
X155519Y1495394D01*
G02X152394Y1498519I-2019J1106D01*
G01X152419Y1498533D01*
X154798Y1500912D01*
Y1526612D01*
X154770Y1526659D01*
G02Y1529341I2230J1341D01*
G01X154798Y1529388D01*
Y1554014D01*
X160725Y1559940D01*
G03X160556Y1560607I-283J283D01*
G02X163793Y1563844I744J2493D01*
G03X164460Y1563675I384J114D01*
G01X165280Y1564496D01*
G03X165251Y1565088I-283J283D01*
G02X168912Y1568749I1647J2014D01*
G03X169504Y1568720I309J254D01*
G01X172486Y1571702D01*
X176827D01*
X176854Y1571710D01*
G02Y1567290I646J-2210D01*
G01X176827Y1567298D01*
G37*
G36*
G01X146668Y1539765D02*
G03X146071Y1539498I-204J-344D01*
G02X145748Y1538659I-2553J501D01*
G01X145720Y1538612D01*
Y1530340D01*
G03X146370Y1530028I400J0D01*
G02X147707Y1525415I1630J-2028D01*
G03X147379Y1524734I-45J-398D01*
G01X149702Y1522412D01*
Y1506388D01*
X149730Y1506341D01*
G02Y1503659I-2230J-1341D01*
G01X149702Y1503612D01*
Y1498673D01*
X149710Y1498646D01*
G02X145290I-2210J-646D01*
G01X145298Y1498673D01*
Y1503612D01*
X145270Y1503659D01*
G02Y1506341I2230J1341D01*
G01X145298Y1506388D01*
Y1520588D01*
X141316Y1524570D01*
Y1538612D01*
X141288Y1538659D01*
G02Y1541341I2230J1341D01*
G01X141316Y1541388D01*
Y1566847D01*
X141308Y1566874D01*
G02X145728I2210J646D01*
G01X145720Y1566847D01*
Y1566340D01*
G03X146370Y1566028I400J0D01*
G02Y1561972I1630J-2028D01*
G03X145720Y1561660I-250J-312D01*
G01Y1560340D01*
G03X146370Y1560028I400J0D01*
G02Y1555972I1630J-2028D01*
G03X145720Y1555660I-250J-312D01*
G01Y1552340D01*
G03X146370Y1552028I400J0D01*
G02Y1547972I1630J-2028D01*
G03X145720Y1547660I-250J-312D01*
G01Y1544340D01*
G03X146370Y1544028I400J0D01*
G02X146668Y1539765I1630J-2028D01*
G37*
G36*
G01X52706Y1584329D02*
G03X53332Y1584302I324J235D01*
G02X53194Y1581071I1968J-1702D01*
G03X52568Y1581098I-324J-235D01*
G02X52706Y1584329I-1968J1702D01*
G37*
G36*
G01Y1590829D02*
G03X53332Y1590802I324J235D01*
G02X53194Y1587571I1968J-1702D01*
G03X52568Y1587598I-324J-235D01*
G02X52706Y1590829I-1968J1702D01*
G37*
G36*
G01Y1596829D02*
G03X53332Y1596802I324J235D01*
G02X53194Y1593571I1968J-1702D01*
G03X52568Y1593598I-324J-235D01*
G02X52706Y1596829I-1968J1702D01*
G37*
G36*
G01Y1602829D02*
G03X53332Y1602802I324J235D01*
G02X53194Y1599571I1968J-1702D01*
G03X52568Y1599598I-324J-235D01*
G02X52706Y1602829I-1968J1702D01*
G37*
G36*
G01X67284Y1521702D02*
G03X66601Y1521419I-283J-283D01*
G01X66602Y1512926D01*
X87264Y1492264D01*
G02X87543Y1488055I-2264J-2264D01*
G01X87502Y1488001D01*
Y1487691D01*
G03X87843Y1487549I200J0D01*
G01X88703Y1488410D01*
X88700Y1488498D01*
G02X91302Y1485998I2600J102D01*
G01Y1465971D01*
X91366Y1465911D01*
G02Y1462089I-1766J-1911D01*
G01X91302Y1462029D01*
Y1452995D01*
X89497Y1451190D01*
X89500Y1451102D01*
G02X86798Y1448400I-2600J-102D01*
G01X86710Y1448403D01*
X86302Y1447995D01*
Y1442514D01*
X86527D01*
X86552Y1442520D01*
G02X86571Y1442525I672J-2514D01*
G01X86625Y1442538D01*
X90488Y1446402D01*
X90788D01*
X93320Y1448933D01*
X93334Y1448987D01*
G02X95231Y1450884I2525J-628D01*
G01X95285Y1450898D01*
X97598Y1453212D01*
Y1454212D01*
X97569Y1454260D01*
G02X102031I2231J1340D01*
G01X102002Y1454212D01*
Y1451388D01*
X98398Y1447785D01*
X98384Y1447731D01*
G02X96487Y1445834I-2525J628D01*
G01X96433Y1445820D01*
X92612Y1441998D01*
X92312D01*
X90663Y1440350D01*
X93502Y1437512D01*
Y1429388D01*
X90532Y1426418D01*
X90491D01*
X90436Y1426372D01*
G02X90402Y1426345I-1448J1789D01*
G01X90392Y1426337D01*
X90024Y1425970D01*
X89677D01*
X89649Y1425962D01*
G02X87042Y1426961I-649J2209D01*
G03X86302Y1426751I-340J-210D01*
G01Y1422605D01*
X90705Y1418202D01*
X97629D01*
X97689Y1418266D01*
Y1418267D01*
G02X102156Y1416989I1911J-1767D01*
G03X102876Y1416835I393J75D01*
G02X107764Y1417264I2624J-1835D01*
G01X109002Y1416026D01*
Y1255990D01*
X101102Y1248090D01*
Y1174974D01*
X91264Y1165136D01*
G02X86736Y1169664I-2264J2264D01*
G01X94698Y1177626D01*
Y1250742D01*
X102598Y1258642D01*
Y1413647D01*
X102580Y1413686D01*
G02X102319Y1414641I2921J1311D01*
G03X101612Y1414850I-398J-45D01*
G02X97689Y1414734I-2012J1650D01*
G01X97629Y1414798D01*
X89295D01*
X82898Y1421195D01*
Y1449405D01*
X84303Y1450810D01*
X84300Y1450898D01*
G02X87002Y1453600I2600J102D01*
G01X87090Y1453597D01*
X87898Y1454405D01*
Y1462029D01*
X87834Y1462089D01*
G02Y1465911I1766J1911D01*
G01X87898Y1465971D01*
Y1468405D01*
G03X87216Y1468688I-400J0D01*
G01X85764Y1467236D01*
G02X81051Y1471563I-2264J2264D01*
G01X81098Y1471619D01*
Y1489374D01*
X60198Y1510274D01*
Y1516293D01*
G03X59626Y1516654I-400J0D01*
G02X56333Y1517560I-1126J2346D01*
G03X55667I-333J-222D01*
G02Y1520440I-2167J1440D01*
G03X56333I333J222D01*
G02X59626Y1521346I2167J-1440D01*
G03X60198Y1521707I172J361D01*
G01Y1538013D01*
G03X59759Y1538411I-400J0D01*
G02X57197Y1539790I-259J2589D01*
G03X56504Y1539816I-354J-186D01*
G02X56603Y1542410I-2204J1383D01*
G03X57296Y1542384I354J186D01*
G02X59759Y1543589I2203J-1384D01*
G03X60198Y1543987I39J398D01*
G01Y1560069D01*
G03X59492Y1560326I-400J0D01*
G02Y1563674I-1992J1674D01*
G03X60198Y1563931I306J257D01*
G01Y1604993D01*
G03X59626Y1605354I-400J0D01*
G02Y1610046I-1126J2346D01*
G03X60198Y1610407I172J361D01*
G01Y1623302D01*
X49500Y1634000D01*
Y1743981D01*
G03X49007Y1744370I-400J0D01*
G02Y1749430I-607J2530D01*
G03X49500Y1749819I93J389D01*
G01Y1861000D01*
X62000Y1873500D01*
X120500D01*
X132500Y1861500D01*
Y1786500D01*
X136000Y1783000D01*
X140500D01*
X143000Y1780500D01*
Y1777000D01*
X140500Y1774500D01*
X135500D01*
X132500Y1771500D01*
Y1677000D01*
X140000Y1669500D01*
X184500D01*
X186500Y1667500D01*
Y1635000D01*
X180000Y1628500D01*
X179900D01*
X174100Y1622700D01*
X171859D01*
X171458Y1622298D01*
X148005D01*
X143205Y1617498D01*
X120382D01*
X117546Y1614663D01*
G03X117586Y1614063I283J-282D01*
G02X113469Y1612605I-1586J-2063D01*
G03X113080Y1613098I-389J93D01*
G01X92117D01*
X91702Y1612683D01*
Y1607305D01*
G03X92421Y1607065I400J1D01*
G02Y1603935I2079J-1565D01*
G03X91702Y1603695I-319J-241D01*
G01Y1570325D01*
G03X92354Y1570016I400J1D01*
G02Y1565984I1646J-2016D01*
G03X91702Y1565675I-252J-310D01*
G01Y1564325D01*
G03X92354Y1564016I400J1D01*
G02Y1559984I1646J-2016D01*
G03X91702Y1559675I-252J-310D01*
G01Y1558325D01*
G03X92354Y1558016I400J1D01*
G02Y1553984I1646J-2016D01*
G03X91702Y1553675I-252J-310D01*
G01Y1552325D01*
G03X92354Y1552016I400J1D01*
G02X95340Y1547769I1646J-2016D01*
G03X95263Y1547144I206J-343D01*
G01X98715Y1543691D01*
G03X99398Y1543977I283J283D01*
G02X101977Y1541398I2602J23D01*
G03X101691Y1540715I-3J-400D01*
G01X125405Y1517002D01*
X128658D01*
X135114Y1510546D01*
X135188Y1510540D01*
G02X137305Y1508101I-180J-2295D01*
G01X138310Y1507097D01*
X138398Y1507100D01*
G02X139279Y1506983I103J-2600D01*
G03X139798Y1507364I119J381D01*
G01Y1510088D01*
X132541Y1517345D01*
X132526Y1517356D01*
G02X131858Y1518024I1475J2143D01*
G01X131856Y1518026D01*
X131845Y1518041D01*
X131798Y1518088D01*
Y1518112D01*
X131770Y1518160D01*
G02X131511Y1518742I2230J1341D01*
G01Y1518743D01*
X131496Y1518791D01*
X127426Y1522860D01*
G03X126791Y1522767I-283J-283D01*
G02X123267Y1526291I-2291J1233D01*
G03X123360Y1526926I-190J352D01*
G01X121926Y1528360D01*
G03X121291Y1528267I-283J-283D01*
G02X117767Y1531791I-2291J1233D01*
G03X117860Y1532426I-190J352D01*
G01X114235Y1536051D01*
G03X113626Y1535999I-283J-283D01*
G02X109999Y1539626I-2126J1501D01*
G03X110051Y1540235I-231J326D01*
G01X106298Y1543988D01*
Y1555112D01*
X106269Y1555160D01*
G02Y1557840I2231J1340D01*
G01X106298Y1557888D01*
Y1568327D01*
X106290Y1568354D01*
G02X110710I2210J646D01*
G01X110702Y1568327D01*
Y1557888D01*
X110731Y1557840D01*
G02Y1555160I-2231J-1340D01*
G01X110702Y1555112D01*
Y1545812D01*
X111232Y1545281D01*
X111446Y1545495D01*
X111430Y1545595D01*
G02X114069Y1543399I2570J405D01*
G03X113797Y1542716I11J-400D01*
G01X118716Y1537797D01*
G03X119399Y1538069I283J283D01*
G02X122069Y1535399I2601J-69D01*
G03X121797Y1534716I11J-400D01*
G01X134450Y1522064D01*
X134510Y1522052D01*
G02X136600Y1519589I-510J-2551D01*
G01X136603Y1519510D01*
X144202Y1511912D01*
Y1495473D01*
X144210Y1495446D01*
G02X139790I-2210J-646D01*
G01X139798Y1495473D01*
Y1501636D01*
G03X139279Y1502017I-400J0D01*
G02X137894Y1501970I-778J2483D01*
G03X137428Y1501437I-93J-389D01*
G02X132691Y1499300I-2428J-937D01*
G03X132025Y1499366I-355J-185D01*
G02X127975I-2025J1634D01*
G03X127309Y1499300I-311J-251D01*
G02X127199Y1499109I-2308J1202D01*
G01X127169Y1499060D01*
Y1498802D01*
X127712D01*
X133382Y1493132D01*
G02X130268Y1490018I-1082J-2032D01*
G01X125888Y1494398D01*
X94588D01*
X81326Y1507661D01*
X81272Y1507675D01*
G02X79375Y1509572I628J2525D01*
G01X79361Y1509626D01*
X75237Y1513750D01*
G03X74561Y1513538I-282J-283D01*
G02X71538Y1516561I-2561J462D01*
G03X71750Y1517237I-71J394D01*
G01X67284Y1521702D01*
G37*
G36*
G01X133333Y473060D02*
G03X132667I-333J-222D01*
G02Y475940I-2167J1440D01*
G03X133333I333J222D01*
G02Y473060I2167J-1440D01*
G37*
G36*
G01Y466560D02*
G03X132667I-333J-222D01*
G02Y469440I-2167J1440D01*
G03X133333I333J222D01*
G02Y466560I2167J-1440D01*
G37*
G36*
G01Y459560D02*
G03X132667I-333J-222D01*
G02Y462440I-2167J1440D01*
G03X133333I333J222D01*
G02Y459560I2167J-1440D01*
G37*
G36*
G01Y452560D02*
G03X132667I-333J-222D01*
G02Y455440I-2167J1440D01*
G03X133333I333J222D01*
G02Y452560I2167J-1440D01*
G37*
G36*
G01X65723Y449050D02*
G03Y448450I264J-300D01*
G02X62277I-1723J-1950D01*
G03Y449050I-264J300D01*
G02Y452950I1723J1950D01*
G03Y453550I-264J300D01*
G02Y457450I1723J1950D01*
G03Y458050I-264J300D01*
G02X61974Y461633I1723J1950D01*
G03X61881Y462219I-311J251D01*
G02X61147Y465861I1419J2181D01*
G03X61054Y466407I-331J225D01*
G02X60787Y470367I1546J2093D01*
G03X60774Y470953I-278J287D01*
G02X60599Y474677I1726J1947D01*
G03Y475223I-292J273D01*
G02X64401I1901J1777D01*
G03Y474677I292J-273D01*
G02X64313Y471033I-1901J-1777D01*
G03X64326Y470447I278J-287D01*
G02X64753Y467039I-1726J-1947D01*
G03X64846Y466493I331J-225D01*
G02X65326Y462767I-1546J-2093D01*
G03X65419Y462181I311J-251D01*
G02X65723Y458050I-1419J-2181D01*
G03Y457450I264J-300D01*
G02Y453550I-1723J-1950D01*
G03Y452950I264J-300D01*
G02Y449050I-1723J-1950D01*
G37*
G36*
G01X75262Y420919D02*
G03X75302Y420253I240J-320D01*
G02X72438Y420081I-1302J-2253D01*
G03X72398Y420747I-240J320D01*
G02X75262Y420919I1302J2253D01*
G37*
G36*
G01X118043Y457384D02*
G02X115957I-1043J-2384D01*
G03Y458116I-161J366D01*
G02Y462884I1043J2384D01*
G03Y463616I-161J366D01*
G02Y468384I1043J2384D01*
G03Y469116I-161J366D01*
G02X118043I1043J2384D01*
G03Y468384I161J-366D01*
G02Y463616I-1043J-2384D01*
G03Y462884I161J-366D01*
G02Y458116I-1043J-2384D01*
G03Y457384I161J-366D01*
G37*
G36*
G01X83340Y409363D02*
G02Y411637I-2340J1137D01*
G03X84060I360J175D01*
G02X88784Y411543I2340J-1137D01*
G03X89516I366J161D01*
G02Y409457I2384J-1043D01*
G03X88784I-366J-161D01*
G02X84060Y409363I-2384J1043D01*
G03X83340I-360J-175D01*
G37*
G36*
G01X89907Y1061969D02*
G03X89320Y1061823I-230J-327D01*
G02X88493Y1065131I-2320J1177D01*
G03X89080Y1065277I230J327D01*
G02X93134Y1066040I2320J-1177D01*
G03X93666I266J299D01*
G02Y1062160I1734J-1940D01*
G03X93134I-266J-299D01*
G02X89907Y1061969I-1734J1940D01*
G37*
G36*
G01X168006Y480488D02*
G03X167449Y480276I-184J-356D01*
G02X163090Y481746I-2149J824D01*
G01X163098Y481773D01*
Y487988D01*
X160298Y490788D01*
Y527227D01*
X160290Y527254D01*
G02X164034Y529617I2210J646D01*
G03X164566I266J298D01*
G02X168310Y527254I1534J-1717D01*
G01X168302Y527227D01*
Y493812D01*
X171402Y490712D01*
Y484188D01*
X171430Y484141D01*
G02X168006Y480488I-2230J-1341D01*
G37*
G36*
G01X148677Y426240D02*
G02X147423Y424360I1323J-2241D01*
G03X146823Y424760I-396J56D01*
G02X148077Y426640I-1323J2241D01*
G03X148677Y426240I396J-56D01*
G37*
G54D25*
X182500Y1584500D03*
X138500Y1606000D03*
X150500Y1600000D03*
X156000Y1606000D03*
X156500Y1600000D03*
X164000Y1606000D03*
X182500Y1592000D03*
X148000Y1606000D03*
X146000Y1612000D03*
X182500Y1599400D03*
X172000Y1606000D03*
X150500Y1591000D03*
X156500D03*
X150000Y1576000D03*
X156000D03*
X170000Y1541000D03*
X136000Y1568000D03*
Y1542000D03*
Y1536000D03*
Y1562000D03*
Y1555000D03*
Y1548000D03*
X168500Y1533500D03*
X170000Y1555000D03*
X156000Y1570000D03*
X154000Y1564000D03*
X170000Y1548500D03*
X168500Y1526000D03*
X150000Y1570000D03*
X136000Y1528000D03*
X174000Y1522000D03*
X174500Y1503500D03*
Y1509500D03*
X174000Y1515500D03*
X148300Y1465000D03*
X161500Y1227500D03*
X116948Y1892000D03*
X124500Y1892403D03*
X132000Y1892000D03*
X113500Y1605500D03*
X128000Y1606000D03*
X122000Y1600000D03*
X104000Y1605500D03*
X122000Y1612000D03*
X116000Y1600000D03*
X122000Y1592000D03*
X116000D03*
Y1584000D03*
X122000D03*
Y1576000D03*
X116000D03*
X129000Y1555500D03*
X122000Y1558000D03*
X114000Y1552000D03*
X122000D03*
X114000Y1558000D03*
X122000Y1564000D03*
X121800Y1569929D03*
X114000Y1564000D03*
X102000Y1562000D03*
Y1550000D03*
Y1556000D03*
Y1568000D03*
X115900Y1569700D03*
X129000Y1535000D03*
Y1549000D03*
X122000Y1546000D03*
X129000Y1542500D03*
X42000Y1784400D03*
X41600Y1746900D03*
X55400Y1613300D03*
X54500Y1574000D03*
X57000Y1568500D03*
X31600Y1024300D03*
X40000Y659000D03*
X68000Y286000D03*
Y296000D03*
Y320000D03*
Y312000D03*
X76000Y296000D03*
X68000Y304000D03*
X74000Y390000D03*
X66000D03*
X58000D03*
X74000Y408000D03*
X66000D03*
Y418000D03*
Y426000D03*
X58000D03*
X74000Y400000D03*
X66000D03*
X58000D03*
Y408000D03*
Y417500D03*
X58100Y431900D03*
X102000Y312000D03*
X104000Y304000D03*
X94000D03*
Y312000D03*
Y320000D03*
X114000Y296000D03*
X106000D03*
X96000D03*
X86000D03*
X118000Y396000D03*
Y386000D03*
X89800Y446000D03*
X118000Y424000D03*
Y404000D03*
Y414000D03*
X129000Y485500D03*
X120000D03*
X110800Y482600D03*
Y488600D03*
Y494600D03*
X129000Y493500D03*
X120000D03*
X122500Y450500D03*
Y457500D03*
Y463500D03*
X121500Y475500D03*
X122500Y469500D03*
X117000Y449000D03*
X89800Y452900D03*
Y459000D03*
X111500Y473000D03*
X89800Y464800D03*
X120000Y501500D03*
X129000Y517500D03*
X110800Y500600D03*
X84500Y514400D03*
X129000Y501500D03*
Y509500D03*
X110800Y512600D03*
X120000Y517500D03*
X110800Y506600D03*
X120000Y509500D03*
Y523500D03*
X129000D03*
X134000Y396000D03*
Y386000D03*
Y404500D03*
Y414000D03*
Y424000D03*
X137000Y493000D03*
X136500Y485500D03*
X137000Y510000D03*
X137500Y523500D03*
X137000Y501500D03*
X137500Y517500D03*
X97250Y1023500D03*
X142000Y291000D03*
X143400Y318700D03*
X174000Y316000D03*
X164000D03*
X182000Y296000D03*
X172000D03*
X162000D03*
X172000Y310000D03*
X182000D03*
X184000Y303000D03*
X176000Y302000D03*
X166000D03*
X143300Y343400D03*
X151300Y298200D03*
X150000Y386000D03*
Y396000D03*
X161600Y445900D03*
X150000Y404000D03*
Y414000D03*
X161900Y451600D03*
X162000Y457600D03*
X161900Y463300D03*
X173700Y513900D03*
X173500Y506000D03*
X173600Y498800D03*
X157100Y500000D03*
X156800Y515400D03*
Y506900D03*
G54D26*
X165000Y1370500D03*
Y1380500D03*
Y1390500D03*
X15906Y1920394D03*
Y1910394D03*
Y1900394D03*
Y1890394D03*
Y1880394D03*
Y1227323D03*
Y1217323D03*
Y1207323D03*
Y1197323D03*
Y1187323D03*
Y781181D03*
Y771181D03*
Y761181D03*
Y751181D03*
Y741181D03*
Y88110D03*
Y78110D03*
Y68110D03*
Y58110D03*
Y48110D03*
G54D29*
X169606Y204409D03*
X179606Y224409D03*
Y214409D03*
Y204409D03*
X149606Y191889D03*
Y181889D03*
X159606Y191889D03*
Y181889D03*
X169606Y191889D03*
Y181889D03*
X179606Y191889D03*
Y181889D03*
X149606Y171889D03*
Y161889D03*
X159606Y171889D03*
Y161889D03*
X169606Y171889D03*
Y161889D03*
X179606Y171889D03*
Y161889D03*
X90709D03*
X100709D03*
X110709D03*
X80709Y256929D03*
Y266929D03*
Y276929D03*
Y286929D03*
X110709Y256929D03*
Y266929D03*
X100709Y256929D03*
Y266929D03*
X90709Y256929D03*
Y266929D03*
X110709Y276929D03*
Y286929D03*
X100709Y276929D03*
Y286929D03*
X90709Y276929D03*
Y286929D03*
X159606Y266929D03*
X149606Y256929D03*
Y266929D03*
X179606Y276929D03*
Y286929D03*
X169606Y276929D03*
Y286929D03*
X159606Y276929D03*
Y286929D03*
X149606Y276929D03*
Y286929D03*
G54D30*
X112000Y101000D03*
X104500D03*
X93500Y101500D03*
X109500Y62000D03*
X89500Y49500D03*
X99500Y61000D03*
X115000Y76500D03*
X109000D03*
X98500Y73000D03*
X115500Y59500D03*
X97000Y51500D03*
X64500Y53000D03*
X70454Y60031D03*
X46500Y511000D03*
X46000Y516000D03*
X82094Y1112500D03*
X91250Y704700D03*
G54D31*
X31299Y1737638D03*
Y1747638D03*
Y1629941D03*
Y1609941D03*
Y1619941D03*
Y1064587D03*
Y1044587D03*
Y1054587D03*
Y913917D03*
Y923917D03*
Y903917D03*
G54D24*
X152500Y1906000D03*
X150000Y64500D03*
G54D33*
X149606Y119409D03*
X80709D03*
Y329409D03*
X149606D03*
G54D32*
Y139409D03*
X80709D03*
Y309409D03*
X149606D03*
G54D35*
X29921Y1943701D03*
Y1857086D03*
Y1250630D03*
X30000Y1164000D03*
X29921Y804488D03*
Y717874D03*
Y111417D03*
Y24803D03*
G54D34*
X47244Y1900393D03*
Y1467165D03*
Y1207323D03*
Y68110D03*
G54D28*
X179134Y1161417D03*
X179133Y570866D03*
X179134Y78740D03*
X27559Y1811023D03*
Y157480D03*
X179134Y1889764D03*
G54D27*
X178937Y1328740D03*
X161417Y1747835D03*
Y1823031D03*
%LPD*%
G75*
G36*
G01X96412Y1498802D02*
X84438Y1510775D01*
X84425Y1510829D01*
G03X82529Y1512725I-2525J-629D01*
G01X82475Y1512738D01*
X69902Y1525312D01*
Y1568027D01*
X69910Y1568054D01*
G03X67105Y1570924I-2210J646D01*
G02X66602Y1571310I-103J386D01*
G01Y1601425D01*
G02X67228Y1601755I400J0D01*
G03X71208Y1604592I1472J2145D01*
G02X71595Y1605098I386J106D01*
G03X71945Y1605121I5J2602D01*
G02X72398Y1604724I53J-397D01*
G01Y1600412D01*
Y1600411D01*
Y1542695D01*
X80210Y1534884D01*
G02X79937Y1534201I-283J-283D01*
G03X82601Y1531537I63J-2601D01*
G02X83284Y1531810I400J-10D01*
G01X88418Y1526676D01*
G02X88104Y1525994I-283J-283D01*
G03X90494Y1523604I-204J-2594D01*
G02X91176Y1523918I399J31D01*
G01X93114Y1521980D01*
G02X92853Y1521298I-283J-283D01*
G03X91908Y1516338I147J-2598D01*
G02X92041Y1515712I-168J-363D01*
G03X95092Y1516362I1959J-1712D01*
G02X94959Y1516988I168J363D01*
G03X95598Y1518553I-1959J1713D01*
G02X96280Y1518814I399J-22D01*
G01X107051Y1508043D01*
G02X106909Y1507702I-142J-141D01*
G01X106471D01*
X106411Y1507766D01*
G03Y1504234I-1911J-1766D01*
G01X106471Y1504298D01*
X106695D01*
G02X106935Y1503579I-1J-400D01*
G03X106826Y1499508I1565J-2079D01*
G02X106569Y1498802I-257J-306D01*
G01X96412D01*
G37*
G36*
G01X55500Y1630000D02*
X52000Y1633500D01*
Y1747559D01*
G02X52480Y1747951I400J0D01*
G03Y1753049I520J2549D01*
G02X52000Y1753441I-80J392D01*
G01Y1753716D01*
X52212D01*
X52224Y1753715D01*
G03X52415Y1758300I276J2285D01*
G02X52000Y1758700I-15J400D01*
G01Y1859500D01*
X64000Y1871500D01*
X119500D01*
X128000Y1863000D01*
Y1785500D01*
X125500Y1783000D01*
X117000D01*
X114500Y1780500D01*
Y1777000D01*
X117000Y1774500D01*
X126000D01*
X128000Y1772500D01*
Y1676500D01*
X137000Y1667500D01*
X181500D01*
X183500Y1665500D01*
Y1634000D01*
X179500Y1630000D01*
X55500D01*
G37*
G36*
G01X86302Y1429591D02*
Y1437040D01*
G02X86768Y1437434I400J0D01*
G03X87296Y1437400I430J2566D01*
G01X87384Y1437403D01*
X89098Y1435688D01*
Y1431212D01*
X88708Y1430822D01*
X88649D01*
X88130Y1430303D01*
X88095Y1430288D01*
G03X87042Y1429381I906J-2116D01*
G02X86302Y1429591I-340J210D01*
G37*
%LPC*%
G75*
G54D25*
X73900Y1535900D03*
X85200Y1515000D03*
X56500Y1769300D03*
G54D27*
X96457Y1747835D03*
Y1823031D03*
%LPD*%
G75*
G54D10*
G01X63500Y63500D02*
Y65000D01*
X47824Y80676D01*
Y165176D01*
X45800Y167200D01*
Y183000D01*
X41400Y187400D01*
Y204700D01*
X45420Y208720D01*
Y235600D01*
X34600Y246420D01*
Y256300D01*
X30100Y260800D01*
Y333094D01*
X26100Y337094D01*
Y364895D01*
X21121Y369874D01*
Y449060D01*
X19254Y450927D01*
Y464554D01*
X30800Y476100D01*
Y526900D01*
X43000Y539100D01*
Y577500D01*
X64000Y598500D01*
Y612900D01*
X69600Y618500D01*
Y662700D01*
G01X15906Y491339D02*
X21456Y496889D01*
Y526544D01*
X17621Y530379D01*
Y560121D01*
X27369Y569869D01*
Y573431D01*
X27000Y573800D01*
G01X38000Y589500D02*
Y588500D01*
X27000Y577500D01*
Y573800D01*
G01X15906Y1457165D02*
X11921Y1453180D01*
Y1382684D01*
X68800Y1325805D01*
Y1178800D01*
G01X56927Y1130027D02*
X72300Y1145400D01*
Y1154900D01*
X75263Y1157863D01*
Y1329937D01*
X17621Y1387579D01*
Y1432121D01*
X21456Y1435956D01*
Y1486990D01*
X14121Y1494325D01*
Y1640215D01*
X16601Y1642695D01*
Y1769728D01*
X39179Y1792306D01*
G01X51200Y827000D02*
Y780700D01*
X39794Y769294D01*
Y754206D01*
X42400Y751600D01*
Y703100D01*
X46600Y698900D01*
Y597600D01*
X38500Y589500D01*
X38000D01*
G01X61207Y828350D02*
X62750Y826807D01*
Y682005D01*
X67525Y677230D01*
Y664775D01*
X69600Y662700D01*
G01X56927Y1130027D02*
X48800Y1121900D01*
Y913200D01*
X64600Y897400D01*
Y882700D01*
G01X60900Y893000D02*
X61600Y892300D01*
Y885200D01*
G01X60900Y893000D02*
Y897500D01*
X46600Y911800D01*
Y1123100D01*
X68400Y1144900D01*
Y1168200D01*
X67250Y1169350D01*
Y1177250D01*
X68800Y1178800D01*
G01X58500Y912500D02*
Y907000D01*
X67200Y898300D01*
Y888800D01*
G01X51000Y1018000D02*
X51025Y1017975D01*
Y923975D01*
X58500Y916500D01*
Y912500D01*
G01X83000Y1619703D02*
X80700Y1617403D01*
Y1546300D01*
X120500Y1506500D01*
X121000D01*
G01X141300Y1625000D02*
X82073D01*
X76300Y1619227D01*
Y1612972D01*
X76299Y1612971D01*
Y1602029D01*
X76300Y1602028D01*
Y1544312D01*
X113000Y1507612D01*
Y1506500D01*
G01X113200Y1622800D02*
X83000D01*
X82104Y1621904D01*
X82089D01*
X78500Y1618315D01*
Y1612060D01*
X78499Y1612059D01*
Y1602941D01*
X78500Y1602940D01*
Y1545224D01*
X117000Y1506724D01*
Y1506500D01*
G01X169876Y1626303D02*
X168679Y1627500D01*
X81461D01*
X74100Y1620139D01*
Y1613884D01*
X74099Y1613883D01*
Y1601117D01*
X74100Y1601116D01*
Y1543400D01*
X109000Y1508500D01*
Y1506500D01*
G01X86500Y723500D02*
Y795000D01*
X105763Y814263D01*
G01X114900Y824100D02*
Y823400D01*
X105763Y814263D01*
G01X131174Y1412700D02*
X131179Y1412695D01*
Y1096321D01*
X139376Y1088124D01*
Y1078814D01*
X139375Y1078813D01*
Y1076929D01*
X139378Y1076926D01*
Y1024147D01*
X141225Y1022300D01*
Y1013275D01*
X161700Y992800D01*
X165382D01*
X169525Y988657D01*
Y849156D01*
X150625Y830256D01*
Y734975D01*
X155292Y730308D01*
Y694592D01*
X155125Y694425D01*
Y679575D01*
X155200Y679500D01*
G01X99600Y1416500D02*
X90000D01*
X84600Y1421900D01*
Y1448700D01*
X86900Y1451000D01*
G01X133799Y1440699D02*
X134600Y1439898D01*
Y1423649D01*
X131174Y1420223D01*
Y1412700D01*
G01X86900Y1451000D02*
X89600Y1453700D01*
Y1464000D01*
G01D02*
Y1486900D01*
X91300Y1488600D01*
G01X110000Y1429500D02*
X111500Y1431000D01*
X121500D01*
X127000Y1436500D01*
X132000D01*
G01X117000Y1435200D02*
X120191D01*
X122500Y1437509D01*
G01D02*
X125690Y1440699D01*
X133799D01*
G01X121000Y1506500D02*
Y1503500D01*
X119500Y1502000D01*
Y1501000D01*
G01X108500Y1501500D02*
X113000Y1506000D01*
Y1506500D01*
G01X117000D02*
Y1504300D01*
X114500Y1501800D01*
G01X109000Y1506500D02*
X108500Y1506000D01*
X104500D01*
G01X141500Y1621600D02*
X118800D01*
X114200Y1617000D01*
X90500D01*
X87451Y1613951D01*
Y1548937D01*
X123288Y1513100D01*
X125900D01*
X133000Y1506000D01*
Y1505500D01*
G01X113200Y1619300D02*
X113000Y1619500D01*
X89500D01*
X85251Y1615251D01*
Y1548025D01*
X122376Y1510900D01*
X124598D01*
X128999Y1506499D01*
G01X130000Y1501000D02*
Y1502000D01*
X128999Y1503001D01*
Y1506499D01*
G01X125000Y1506500D02*
Y1500500D01*
G01X83050Y1616000D02*
Y1547114D01*
X121464Y1508700D01*
X122800D01*
X125000Y1506500D01*
G01X135008Y1508245D02*
X127953Y1515300D01*
X124700D01*
X90000Y1550000D01*
Y1613388D01*
X91412Y1614800D01*
X115277D01*
X119677Y1619200D01*
X142500D01*
X147300Y1624000D01*
X170753D01*
X173270Y1626517D01*
G01X157500Y1454800D02*
Y1449000D01*
X156000Y1447500D01*
G01X151500Y1438500D02*
X156000Y1443000D01*
Y1447500D01*
G01X135000Y1500500D02*
Y1502500D01*
X133000Y1504500D01*
Y1505500D01*
G01X138500Y1504500D02*
X135008Y1507992D01*
Y1508245D01*
X-222440Y19685D03*
Y1948818D03*
X29921Y24803D03*
Y111417D03*
Y458031D03*
Y544646D03*
Y717874D03*
Y804488D03*
X30000Y1164000D03*
X29921Y1250630D03*
Y1423858D03*
Y1510472D03*
Y1857086D03*
Y1943701D03*
X47244Y68110D03*
X80709Y119409D03*
Y139409D03*
Y329409D03*
Y309409D03*
X47244Y501338D03*
Y761181D03*
Y1207323D03*
Y1467165D03*
Y1900393D03*
X149606Y119409D03*
Y139409D03*
Y329409D03*
Y309409D03*
X643700Y19685D03*
Y1948818D03*
G54D20*
G01X56800Y691000D02*
X57684Y691884D01*
Y697639D01*
G01X56800Y691000D02*
X56710Y690910D01*
Y681069D01*
G01X56800Y831000D02*
Y698523D01*
X57684Y697639D01*
G01X57500Y844500D02*
X52000Y850000D01*
Y867500D01*
G01X56800Y831000D02*
Y843800D01*
X57500Y844500D01*
G01X52000Y867500D02*
Y881300D01*
X49600Y883700D01*
Y889400D01*
G01D02*
Y903448D01*
X41675Y911373D01*
Y931224D01*
X41000Y931899D01*
G01X39300Y1105800D02*
X41675Y1103425D01*
Y932574D01*
X41000Y931899D01*
G01X39300Y1105800D02*
X41400Y1107900D01*
Y1123900D01*
X61500Y1144000D01*
Y1162700D01*
X64500Y1165700D01*
G01X85000Y1490000D02*
X76500Y1498500D01*
G01D02*
X63400Y1511600D01*
Y1625600D01*
X55000Y1634000D01*
G01X105500Y1415000D02*
X105800Y1414700D01*
Y1257316D01*
X97900Y1249416D01*
Y1176300D01*
X89000Y1167400D01*
G01X85000Y1490000D02*
X84300Y1489300D01*
Y1470300D01*
X83500Y1469500D01*
G54D11*
X-181139Y20007D03*
X-180444Y1947256D03*
X150000Y64500D03*
X152500Y1906000D03*
X601704Y21248D03*
X602399Y1948497D03*
G54D21*
G01X15906Y83908D02*
Y88110D01*
G01D02*
Y92312D01*
G01X11704Y88110D02*
X15906D01*
G01D02*
X20108D01*
G01X27559Y140328D02*
Y157480D01*
G01D02*
Y174632D01*
G01X10407Y157480D02*
X27559D01*
G01D02*
X44711D01*
G01X27559Y612769D02*
Y629921D01*
G01D02*
Y647073D01*
G01X15906Y776979D02*
Y781181D01*
G01D02*
Y785383D01*
G01X11704Y781181D02*
X15906D01*
G01D02*
X20108D01*
G01X15906Y1223121D02*
Y1227323D01*
G01D02*
Y1231525D01*
G01X11704Y1227323D02*
X15906D01*
G01D02*
X20108D01*
G01X17716Y1321431D02*
Y1338583D01*
G01D02*
Y1355735D01*
G01Y1338583D02*
X34868D01*
G01X15906Y1482963D02*
Y1487165D01*
G01X12735Y1483994D02*
X15906Y1487165D01*
G01X27559Y1793871D02*
Y1811023D01*
G01D02*
Y1828175D01*
G01X10407Y1811023D02*
X27559D01*
G01D02*
X44711D01*
G01X15906Y1916192D02*
Y1920394D01*
G01D02*
Y1924596D01*
G01X11704Y1920394D02*
X15906D01*
G01D02*
X20108D01*
G01X76457Y171889D02*
X80709D01*
G01X77502Y168682D02*
X80709Y171889D01*
G01Y157637D02*
Y161889D01*
G01D02*
X84961D01*
G01X76305Y1747835D02*
X96457D01*
G01X76305Y1823031D02*
X96457D01*
G01X90709Y167637D02*
Y171889D01*
G01D02*
X94961D01*
G01X90709Y157637D02*
Y161889D01*
G01D02*
Y166141D01*
G01X86457Y161889D02*
X90709D01*
G01D02*
X94961D01*
G01X100709Y167637D02*
Y171889D01*
G01X96457D02*
X100709D01*
G01D02*
X104961D01*
G01X100709Y157637D02*
Y161889D01*
G01D02*
Y166141D01*
G01X96457Y161889D02*
X100709D01*
G01D02*
X104961D01*
G01X110709Y167637D02*
Y171889D01*
G01X106457D02*
X110709D01*
G01D02*
X114961D01*
G01X110709Y157637D02*
Y161889D01*
G01D02*
Y166141D01*
G01X106457Y161889D02*
X110709D01*
G01D02*
X114961D01*
G01X90709Y244409D02*
Y248661D01*
G01Y244409D02*
X94961D01*
G01X96457Y1727683D02*
Y1747835D01*
G01D02*
Y1767987D01*
G01Y1747835D02*
X116609D01*
G01X96457Y1802879D02*
Y1823031D01*
G01D02*
Y1843183D01*
G01Y1823031D02*
X116609D01*
G01X179134Y61588D02*
Y78740D01*
G01D02*
Y95892D01*
G01X161982Y78740D02*
X179134D01*
G01D02*
X196286D01*
G01X149606Y187637D02*
Y191889D01*
G01Y177637D02*
Y181889D01*
G01D02*
Y186141D01*
G01X145354Y181889D02*
X149606D01*
G01D02*
X153858D01*
G01X159606Y187637D02*
Y191889D01*
G01Y177637D02*
Y181889D01*
G01D02*
Y186141D01*
G01X155354Y181889D02*
X159606D01*
G01D02*
X163858D01*
G01X169606Y187637D02*
Y191889D01*
G01Y177637D02*
Y181889D01*
G01D02*
Y186141D01*
G01X165354Y181889D02*
X169606D01*
G01D02*
X173858D01*
G01X179606Y187637D02*
Y191889D01*
G01Y177637D02*
Y181889D01*
G01D02*
Y186141D01*
G01X175354Y181889D02*
X179606D01*
G01D02*
X183858D01*
G01X149606Y167637D02*
Y171889D01*
G01D02*
Y176141D01*
G01X145354Y171889D02*
X149606D01*
G01D02*
X153858D01*
G01X149606Y157637D02*
Y161889D01*
G01D02*
Y166141D01*
G01X145354Y161889D02*
X149606D01*
G01D02*
X153858D01*
G01X159606Y167637D02*
Y171889D01*
G01D02*
Y176141D01*
G01X155354Y171889D02*
X159606D01*
G01D02*
X163858D01*
G01X159606Y157637D02*
Y161889D01*
G01D02*
Y166141D01*
G01X155354Y161889D02*
X159606D01*
G01D02*
X163858D01*
G01X169606Y167637D02*
Y171889D01*
G01D02*
Y176141D01*
G01X165354Y171889D02*
X169606D01*
G01D02*
X173858D01*
G01X169606Y157637D02*
Y161889D01*
G01D02*
Y166141D01*
G01X165354Y161889D02*
X169606D01*
G01D02*
X173858D01*
G01X179606Y167637D02*
Y171889D01*
G01D02*
Y176141D01*
G01X175354Y171889D02*
X179606D01*
G01D02*
X183858D01*
G01X179606Y157637D02*
Y161889D01*
G01D02*
Y166141D01*
G01X175354Y161889D02*
X179606D01*
G01D02*
X183858D01*
G01X159606Y200157D02*
Y204409D01*
G01X155354D02*
X159606D01*
G01D02*
X163858D01*
G01X149606Y191889D02*
Y196141D01*
G01X145354Y191889D02*
X149606D01*
G01D02*
X153858D01*
G01X159606D02*
Y196141D01*
G01X155354Y191889D02*
X159606D01*
G01D02*
X163858D01*
G01X169606D02*
Y196141D01*
G01X165354Y191889D02*
X169606D01*
G01D02*
X173858D01*
G01X179606D02*
Y196141D01*
G01X175354Y191889D02*
X179606D01*
G01D02*
X183858D01*
G01X159606Y244409D02*
Y248661D01*
G01X155354Y244409D02*
X159606D01*
G01X179133Y553714D02*
Y570866D01*
G01D02*
Y588018D01*
G01X161981Y570866D02*
X179133D01*
G01D02*
X196285D01*
G01X179134Y1144265D02*
Y1161417D01*
G01D02*
Y1178569D01*
G01X161982Y1161417D02*
X179134D01*
G01D02*
X196286D01*
G01X178937Y1308588D02*
Y1328740D01*
G01D02*
Y1348892D01*
G01X158785Y1328740D02*
X178937D01*
G01D02*
X199089D01*
G01X161417Y1727683D02*
Y1747835D01*
G01D02*
Y1767987D01*
G01X141265Y1747835D02*
X161417D01*
G01D02*
X181569D01*
G01X161417Y1802879D02*
Y1823031D01*
G01D02*
Y1843183D01*
G01X141265Y1823031D02*
X161417D01*
G01D02*
X181569D01*
G01X179134Y1872612D02*
Y1889764D01*
G01D02*
Y1906916D01*
G01X161982Y1889764D02*
X179134D01*
G01D02*
X196286D01*
G54D12*
X8594Y6500D03*
X20000Y6000D03*
X17000Y36500D03*
X5594Y87000D03*
Y53500D03*
X29500Y53000D03*
X26000Y87000D03*
X30800Y130300D03*
X4594Y120500D03*
X23500Y124000D03*
X15000Y131500D03*
X14500Y100500D03*
Y112500D03*
X4500Y105500D03*
X5000Y137500D03*
X22500Y190000D03*
X29700Y191400D03*
X5594Y153500D03*
X4594Y187500D03*
X16500Y175000D03*
X15500Y143500D03*
X27000Y182000D03*
X14000Y184000D03*
X4500Y170500D03*
X21500Y241500D03*
X4594Y234000D03*
X24000Y212000D03*
X29000Y200500D03*
X13500Y230500D03*
X13000Y212500D03*
X5000Y221000D03*
X12500Y197500D03*
X4500Y202500D03*
X28050Y256950D03*
X5094Y278000D03*
X6094Y257000D03*
X13500Y279000D03*
X13000Y244000D03*
X12500Y266500D03*
X5500Y269500D03*
X5000Y247500D03*
X19721Y267203D03*
X5594Y312000D03*
X5304Y342500D03*
X4900Y328000D03*
X13500Y303500D03*
X13000Y321000D03*
X13500Y295000D03*
X5500Y295500D03*
X6500Y375000D03*
X27000Y371000D03*
X4800Y356200D03*
X23700Y363900D03*
X29500Y364500D03*
X27000Y377500D03*
Y384000D03*
Y389500D03*
X4594Y421000D03*
X5304Y444500D03*
Y440500D03*
X5000Y408500D03*
X5304Y434500D03*
X4594Y396500D03*
X26500Y440000D03*
X26000Y432500D03*
X23800Y410700D03*
X5094Y469500D03*
X5000Y495000D03*
X4700Y458200D03*
X5000Y486500D03*
X5094Y600000D03*
X13510Y597990D03*
X18035Y572076D03*
X14000Y614000D03*
X4594Y625000D03*
X18000Y608000D03*
X6000Y612000D03*
Y646000D03*
X26000Y656500D03*
X5594Y688500D03*
X5304Y661000D03*
X14000Y659000D03*
X23000Y677500D03*
X8000Y678000D03*
X31000Y700500D03*
X20000Y696000D03*
X6000Y698000D03*
X28000Y706000D03*
X31000Y747000D03*
X22000Y746000D03*
X27000Y750000D03*
X26000Y732000D03*
X18000Y724000D03*
Y732500D03*
Y712000D03*
X6000Y706500D03*
Y722000D03*
Y730500D03*
X5594Y778000D03*
X6500Y799000D03*
X9500Y804000D03*
X24000Y756000D03*
X30000Y782000D03*
X16100Y794600D03*
X5594Y844500D03*
X6094Y819500D03*
X30500D03*
X10000Y811500D03*
X24000Y846000D03*
X24500Y853500D03*
X16000Y828000D03*
Y814000D03*
Y856000D03*
Y842000D03*
X4500Y833500D03*
X26053Y828247D03*
X5094Y897500D03*
X5594Y869000D03*
X16000Y906000D03*
X18000Y884000D03*
Y870000D03*
X4500Y857500D03*
X5000Y883500D03*
X18500Y896500D03*
X23053Y861247D03*
X5304Y926000D03*
X4594Y954000D03*
X18000Y934000D03*
Y920000D03*
X16000Y948000D03*
X4500Y913000D03*
Y941500D03*
X26053Y938247D03*
X5594Y984500D03*
X28000Y992000D03*
X16000Y962000D03*
Y990000D03*
Y976000D03*
Y1000000D03*
X4500Y970000D03*
Y997000D03*
X25053Y971247D03*
X4594Y1041500D03*
Y1013500D03*
X6000Y1058000D03*
X26000Y1010000D03*
X16000Y1014000D03*
Y1046000D03*
Y1032000D03*
X14000Y1060000D03*
X4500Y1029500D03*
X27553Y1029247D03*
X5094Y1074500D03*
X28000Y1072000D03*
X14000Y1074000D03*
Y1100000D03*
Y1086000D03*
X16000Y1110000D03*
X6000Y1096000D03*
X26100Y1088600D03*
X27218Y1097000D03*
X16000Y1124000D03*
Y1148000D03*
Y1134000D03*
Y1162000D03*
X6000Y1138000D03*
Y1118000D03*
Y1152000D03*
X26600Y1132400D03*
X24553Y1153247D03*
X5304Y1208000D03*
X4594Y1169500D03*
X24000Y1180000D03*
X16000Y1176000D03*
X8500Y1237000D03*
X30000Y1240000D03*
X16000Y1262000D03*
Y1244000D03*
X6000Y1252000D03*
X22000Y1232000D03*
X6500Y1302000D03*
X5094Y1268500D03*
X17700Y1283000D03*
X12000Y1274000D03*
Y1294000D03*
X28000Y1266000D03*
Y1286000D03*
Y1300000D03*
X19800Y1315400D03*
X13500Y1365000D03*
X6000Y1318000D03*
X28000Y1320000D03*
X30800Y1403900D03*
X5304Y1409400D03*
X4594Y1382000D03*
X7500Y1376500D03*
X8000Y1368000D03*
X30438Y1367562D03*
X4800Y1460700D03*
X4594Y1435500D03*
X5304Y1504100D03*
X4600Y1484800D03*
X29500Y1495800D03*
X5304Y1540500D03*
Y1522100D03*
X26600Y1570100D03*
X26900Y1547900D03*
Y1559100D03*
X4594Y1607500D03*
X5304Y1576200D03*
X26700Y1579800D03*
X7500Y1640200D03*
X5304Y1659000D03*
X4594Y1632000D03*
X29000Y1671000D03*
X19250Y1663100D03*
X13900Y1706200D03*
X5304Y1723500D03*
X4900Y1708000D03*
X4594Y1691000D03*
X4700Y1676100D03*
X30000Y1731000D03*
X4594Y1775000D03*
Y1751000D03*
X12600Y1753800D03*
X13100Y1742600D03*
Y1728900D03*
X12900Y1765200D03*
X4594Y1826500D03*
X5900Y1814100D03*
X4594Y1799500D03*
X12600Y1792800D03*
X12500Y1782500D03*
X4594Y1878500D03*
X12800Y1863700D03*
X5000Y1864100D03*
X18600Y1871400D03*
X4594Y1850000D03*
X24200Y1836700D03*
X15000Y1854900D03*
X14500Y1842000D03*
X27500Y1874500D03*
X24800Y1926500D03*
X5094Y1921000D03*
X4594Y1902000D03*
X24500Y1884000D03*
X13100Y1933900D03*
X16100Y1950700D03*
X5094Y1944500D03*
X15500Y1942500D03*
X4500Y1936000D03*
X6500Y1962000D03*
X25000Y1962500D03*
X12500Y1959000D03*
X63594Y7000D03*
Y25500D03*
X40594Y6000D03*
X49000Y18500D03*
X43000Y27000D03*
X64000Y17000D03*
X53000Y5000D03*
X31500Y5500D03*
X51500Y53000D03*
X74000Y45000D03*
X64500Y40000D03*
X32000D03*
X78400Y86100D03*
X63098Y119103D03*
X52000Y115600D03*
X51700Y131700D03*
X34400Y95300D03*
X71000Y131859D03*
X37000Y124000D03*
X58749Y101151D03*
X62598Y141103D03*
X51900Y145700D03*
X69000Y153000D03*
X73500Y146000D03*
X60800Y147700D03*
X68000Y286000D03*
Y296000D03*
Y320000D03*
Y312000D03*
X76000Y296000D03*
X68000Y304000D03*
X74000Y390000D03*
X66000D03*
X58000D03*
X59104Y441094D03*
X64000Y446500D03*
X74000Y408000D03*
X66000D03*
Y418000D03*
X74000D03*
X73700Y423000D03*
X66000Y426000D03*
X58000D03*
X74000Y400000D03*
X66000D03*
X58000D03*
Y408000D03*
Y417500D03*
X58100Y431900D03*
X63096Y434540D03*
X68500Y434300D03*
X81000Y410500D03*
X82000Y483600D03*
X46000Y490500D03*
X50100Y493000D03*
X42500D03*
X78200Y481700D03*
X63300Y464400D03*
X64000Y451000D03*
Y455500D03*
Y460000D03*
X62500Y472900D03*
X62600Y468500D03*
X62500Y477000D03*
X78500Y506700D03*
X78200Y501000D03*
X71800Y506900D03*
X71900Y501000D03*
X72100Y521800D03*
X79400D03*
X72000Y514800D03*
X78000D03*
X51700Y522500D03*
X74942Y530983D03*
X76166Y551466D03*
X72500Y595900D03*
X56800Y576950D03*
X34100Y566600D03*
X36000Y554000D03*
X79122Y565700D03*
X79458Y578758D03*
X69800Y574200D03*
X38000Y589500D03*
X80900Y668400D03*
X79000Y675500D03*
X56710Y681069D03*
X56800Y691000D03*
X40000Y659000D03*
X43281Y674991D03*
X39096Y674917D03*
X42000Y655500D03*
X69100Y698006D03*
X71800Y701300D03*
X74100Y669398D03*
X32000Y666000D03*
X69600Y662700D03*
X60500Y674700D03*
X80479Y683921D03*
X50000Y712500D03*
Y749000D03*
X40000Y746500D03*
X36000Y730000D03*
X46000Y726000D03*
X44000Y782000D03*
X42000Y802000D03*
Y788000D03*
X47600Y796800D03*
X56800Y831000D03*
X81500Y837500D03*
X82000Y806500D03*
X48000Y816000D03*
X38000Y834000D03*
Y820000D03*
X46000Y848000D03*
Y834000D03*
X32000Y844000D03*
X78300Y832600D03*
X77600Y849100D03*
X48100Y853400D03*
X45600Y827500D03*
X57809Y852500D03*
X52000Y867500D03*
X37500Y907500D03*
X77000Y871500D03*
X79000Y857000D03*
X62500Y862000D03*
X61500Y876500D03*
X78000Y878500D03*
X32000Y858000D03*
Y886000D03*
Y872000D03*
X77500Y907000D03*
X78300Y893900D03*
X77000Y863000D03*
X47000Y877600D03*
X40900Y901500D03*
X60900Y893000D03*
X54200Y926700D03*
X67000Y907300D03*
X41000Y931899D03*
X37500Y912000D03*
X34000Y944000D03*
Y934500D03*
X33500Y953000D03*
X61500Y938500D03*
X81500Y940000D03*
X75500Y936500D03*
X69500Y939000D03*
X55500Y955500D03*
X56500Y940000D03*
X62500Y924500D03*
X70000Y914500D03*
Y925500D03*
X76500Y927000D03*
X77500Y917000D03*
X58500Y912500D03*
X64000Y980500D03*
X33500Y962500D03*
X34000Y984000D03*
Y974500D03*
Y1008000D03*
X55500Y968000D03*
X76400Y999100D03*
X37500Y998000D03*
X37700Y991600D03*
X31600Y1024300D03*
X57500Y1050500D03*
X33600Y1029900D03*
X34000Y1017500D03*
X39300Y1105800D03*
X58500Y1104500D03*
X34000Y1102000D03*
Y1072000D03*
X33550Y1080100D03*
X67302Y1133490D03*
X78292Y1148041D03*
X66000Y1149500D03*
X79044Y1144112D03*
X37500Y1118900D03*
X74000Y1132000D03*
X34000Y1144000D03*
X40000Y1136000D03*
Y1156000D03*
X32000Y1114000D03*
X77293Y1129729D03*
X56927Y1130027D03*
X64500Y1165700D03*
X58000Y1206000D03*
X60000Y1194000D03*
X61000Y1173000D03*
X54000Y1184000D03*
X44000Y1194000D03*
X42000Y1242000D03*
X50000Y1244000D03*
X58000Y1250000D03*
X46000Y1218000D03*
X31500Y1222000D03*
X58000D03*
X39500Y1231000D03*
X51800Y1231600D03*
X50100Y1261500D03*
X31000Y1280500D03*
X42000Y1266000D03*
Y1290000D03*
X34000Y1312000D03*
X40000Y1278000D03*
Y1298000D03*
X44000Y1306000D03*
X58000Y1312000D03*
Y1292000D03*
Y1272000D03*
X52000Y1296300D03*
X61000Y1363500D03*
X38000Y1334000D03*
X50000Y1318000D03*
X44000Y1326000D03*
Y1340000D03*
X54000Y1330000D03*
X72000Y1360000D03*
X31500Y1397500D03*
X81500Y1382000D03*
Y1416500D03*
Y1404000D03*
X52500Y1368500D03*
X71800Y1373900D03*
X70500Y1378500D03*
X69400Y1402900D03*
X39500Y1407900D03*
X55600Y1381700D03*
X48900Y1390500D03*
X60900D03*
X56700Y1400100D03*
X68800Y1417800D03*
X58800Y1412400D03*
X49000Y1413300D03*
X72900Y1393600D03*
X74900Y1408800D03*
X32000Y1391500D03*
X61500Y1380000D03*
X70400Y1444500D03*
X79000Y1436400D03*
X76200Y1430700D03*
X60600Y1423600D03*
X75600Y1420300D03*
X66500Y1433500D03*
X53100Y1430700D03*
X42600Y1444200D03*
X34000Y1465900D03*
X49100Y1448400D03*
X68500Y1454600D03*
X74500Y1461800D03*
X72300Y1469800D03*
X59000Y1444500D03*
X77000Y1449000D03*
X58100Y1459300D03*
X53500Y1519000D03*
X72000Y1514000D03*
X58500Y1519000D03*
X63000Y1482300D03*
X42700Y1500000D03*
X72700Y1480500D03*
X46500Y1484900D03*
X64100Y1495400D03*
X73000Y1491200D03*
X43300Y1518500D03*
X49500Y1505000D03*
X59000Y1472000D03*
X34000Y1477600D03*
X76500Y1498500D03*
X57000Y1568500D03*
X57500Y1562000D03*
X59500Y1541000D03*
X54300Y1541200D03*
X80000Y1531600D03*
X73900Y1535900D03*
X46600Y1541100D03*
X45300Y1563600D03*
X45900Y1532800D03*
X45400Y1523800D03*
X37900Y1570000D03*
X38800Y1541700D03*
X38300Y1561800D03*
X54500Y1574000D03*
X44400Y1592100D03*
X33100Y1587400D03*
X38300Y1579600D03*
X71600Y1607700D03*
X50600Y1589300D03*
Y1582800D03*
Y1595300D03*
Y1601300D03*
X55300Y1601100D03*
Y1595100D03*
Y1582600D03*
Y1589100D03*
X68700Y1603900D03*
X55400Y1613300D03*
X58500Y1607700D03*
X43200Y1634800D03*
X59500Y1667000D03*
X70000Y1668000D03*
X76000Y1646000D03*
Y1634000D03*
X75500Y1659500D03*
X54000Y1646500D03*
X64500Y1646000D03*
X55000Y1634000D03*
X64000D03*
X64500Y1658500D03*
X53500Y1659000D03*
X37000Y1714000D03*
X42500Y1699500D03*
X44600Y1724400D03*
X44900Y1706800D03*
X56000Y1695000D03*
Y1704500D03*
Y1712500D03*
X55500Y1723500D03*
X69000Y1684500D03*
X80500D03*
X62500Y1691500D03*
X65000Y1724000D03*
X62500Y1709000D03*
X72500Y1717000D03*
Y1699000D03*
X75500Y1679000D03*
X62500Y1700000D03*
X38800Y1775000D03*
X41600Y1746900D03*
X48400D03*
X53000Y1750500D03*
X36700Y1764700D03*
X56500Y1769300D03*
X44900Y1740300D03*
X64500Y1758500D03*
X55500Y1735500D03*
X65000Y1735000D03*
X79000Y1766500D03*
X65000Y1749000D03*
Y1768000D03*
Y1742500D03*
X71500Y1760000D03*
X72500Y1733000D03*
X60000Y1730000D03*
X42000Y1784400D03*
X44400Y1821400D03*
X81000Y1802000D03*
X73000Y1813000D03*
X64500Y1821500D03*
Y1812000D03*
Y1801500D03*
X65000Y1790000D03*
X72000Y1798000D03*
X39179Y1792306D03*
X39700Y1869700D03*
X46700Y1857700D03*
X46500Y1850200D03*
X44500Y1833500D03*
X39700Y1846600D03*
X45500Y1865000D03*
X31500Y1878500D03*
X36000Y1835500D03*
X71000Y1864500D03*
X75500Y1838500D03*
X63500Y1863000D03*
Y1856000D03*
X64000Y1844500D03*
Y1834000D03*
X73000Y1847000D03*
X72500Y1830000D03*
X75000Y1882000D03*
X54500Y1889500D03*
X63500Y1928000D03*
X61500Y1922500D03*
X46000Y1923000D03*
X54000Y1928500D03*
X35300Y1925300D03*
X36500Y1900500D03*
X63500Y1963000D03*
X63594Y1935500D03*
X61600Y1954700D03*
X34500Y1963200D03*
X41100Y1957500D03*
X55300Y1959100D03*
X45100Y1933400D03*
X35000Y1933500D03*
X43500Y1945000D03*
X49053Y1951747D03*
X128500Y89000D03*
X118000Y54500D03*
X124000Y74500D03*
X105000Y55000D03*
X85000Y45000D03*
X105000D03*
X95000D03*
X115000D03*
X125000D03*
X127000Y129000D03*
X127700Y119200D03*
X128700Y104200D03*
X131000Y138100D03*
X118000Y124500D03*
X119000Y109500D03*
X95000Y125000D03*
X105000D03*
X95000Y134000D03*
X86000Y152000D03*
X129000Y160100D03*
X131000Y150100D03*
X118000Y154500D03*
Y142500D03*
X95000Y143000D03*
X105000D03*
X95000Y155000D03*
X105000D03*
X131800Y289700D03*
X130900Y259100D03*
X102000Y312000D03*
X104000Y304000D03*
X94000D03*
Y312000D03*
Y320000D03*
X114000Y296000D03*
X106000D03*
X96000D03*
X86000D03*
X111500Y390000D03*
X101300Y390100D03*
X105500Y390000D03*
X118000Y396000D03*
Y386000D03*
X105500Y406500D03*
X101500D03*
X107000Y426500D03*
X98000D03*
X102500D03*
X111200Y426400D03*
X110500Y406500D03*
X89800Y446000D03*
X131000Y447000D03*
X91900Y410500D03*
X84500Y433000D03*
X88500Y426500D03*
X86400Y410500D03*
X118000Y424000D03*
Y404000D03*
X130000Y432000D03*
X118000Y414000D03*
X129000Y485500D03*
X120000D03*
X110800Y482600D03*
X99800Y482000D03*
X110800Y488600D03*
X100000Y488000D03*
Y494000D03*
X110800Y494600D03*
X129000Y493500D03*
X120000D03*
X122500Y450500D03*
Y457500D03*
Y463500D03*
X121500Y475500D03*
X122500Y469500D03*
X117000Y455000D03*
Y460500D03*
Y466000D03*
Y471500D03*
Y449000D03*
X89800Y452900D03*
Y459000D03*
X111500Y473000D03*
X99500D03*
X89800Y464800D03*
X130500Y454000D03*
Y461000D03*
Y468000D03*
Y474500D03*
X120000Y501500D03*
X129000Y517500D03*
X100000Y512000D03*
X110800Y500600D03*
X100000Y500000D03*
X85000Y506400D03*
X84500Y514400D03*
X129000Y501500D03*
Y509500D03*
X110800Y512600D03*
X120000Y517500D03*
X100000Y506000D03*
X110800Y506600D03*
X120000Y509500D03*
Y523500D03*
X129000D03*
X100000Y519100D03*
X117000Y530000D03*
X105300Y525200D03*
X131700Y571100D03*
X103100Y587600D03*
X87595Y581300D03*
X90630Y602020D03*
X82900Y620600D03*
X106400Y648300D03*
X132110Y678353D03*
X86443Y662853D03*
X88967Y659749D03*
X83900D03*
X84504Y666353D03*
X90674Y663367D03*
X84000Y674000D03*
X121500Y683500D03*
X119576Y687008D03*
X120702Y690847D03*
X100600Y656600D03*
Y670600D03*
X112800Y653500D03*
X108200Y655825D03*
X119000Y673300D03*
X87310Y676796D03*
X124800Y696600D03*
X129800Y696800D03*
X98000Y674327D03*
X102913Y673973D03*
X107113Y674001D03*
X108500Y695500D03*
X103500D03*
X99001Y694866D03*
X128600Y669500D03*
X104000Y734000D03*
X125000D03*
X116500Y752000D03*
X125000Y751000D03*
X125500Y741500D03*
X130000Y736500D03*
X120500Y732500D03*
X120000Y717500D03*
X115000Y704500D03*
X106882Y794201D03*
X107000Y798200D03*
Y802400D03*
X123000Y800000D03*
X122500Y792500D03*
X114000Y800000D03*
X113500Y792500D03*
X130000Y800000D03*
X129500Y792500D03*
X121500Y783500D03*
X121000Y776000D03*
X129500Y782000D03*
X129000Y774500D03*
X125000Y758500D03*
X115200Y784200D03*
X115000Y773200D03*
X121000Y767900D03*
X115217Y765517D03*
X111100Y788200D03*
X116402Y779402D03*
X95500Y841500D03*
X82500Y814000D03*
X123500Y842500D03*
Y816000D03*
X123000Y808500D03*
X115000Y813000D03*
X114500Y805500D03*
X129200Y830400D03*
X129800Y813500D03*
X124500Y825100D03*
X90500Y831500D03*
X87000Y839500D03*
X105763Y814263D03*
X85500Y903000D03*
X116053Y903247D03*
X127000Y903000D03*
X90000Y893000D03*
X102500Y893500D03*
X117500Y893000D03*
X125000Y868500D03*
X124500Y858000D03*
X107000Y903000D03*
X124500Y876500D03*
X126000Y892500D03*
X96053Y903247D03*
X83400Y878600D03*
X125500Y944000D03*
X105000Y958000D03*
X86500Y932000D03*
X96500Y916500D03*
X107000Y918000D03*
X115000Y920000D03*
X125500D03*
X126000Y930000D03*
X115500D03*
X99000Y953000D03*
X88500Y940500D03*
X120000Y916000D03*
X124000Y909000D03*
X113500Y909500D03*
X103500D03*
X94000Y910500D03*
X85500Y915000D03*
X126000Y954000D03*
X110000Y949500D03*
X117529Y948844D03*
X93000Y925500D03*
X125000Y967000D03*
X130500Y966000D03*
X124000Y971500D03*
X117000Y1008500D03*
X105500Y996000D03*
X95500Y999000D03*
X87000Y997500D03*
X106500Y1008500D03*
X119000Y975000D03*
X108500Y964000D03*
Y971000D03*
X114800Y1005000D03*
X124618Y959244D03*
X122900Y1007400D03*
X97250Y1023500D03*
X88000Y1034500D03*
X110500Y1041500D03*
X111500Y1030000D03*
Y1020000D03*
X104000Y1014000D03*
X110500Y1051000D03*
X103500Y1042000D03*
Y1028500D03*
X116500Y1049000D03*
Y1035500D03*
X117500Y1023500D03*
X95400Y1064100D03*
X91400D03*
X87000Y1063000D03*
X91500Y1093000D03*
X120000Y1108000D03*
Y1102000D03*
X115000Y1108500D03*
X110500Y1064500D03*
Y1112000D03*
X103500Y1073500D03*
X104500Y1095000D03*
X116500Y1076000D03*
X109000Y1083500D03*
X116500Y1062500D03*
X121000Y1133000D03*
Y1147500D03*
X89000Y1167400D03*
X118500Y1166000D03*
X105000Y1196000D03*
X119300Y1191400D03*
X119500Y1177500D03*
Y1205500D03*
X104500Y1208000D03*
X94000Y1189000D03*
X91500Y1200000D03*
X99000Y1265500D03*
X117500Y1251000D03*
X112000Y1250500D03*
Y1244500D03*
X119300Y1245400D03*
Y1219400D03*
X119500Y1231500D03*
X104500Y1219500D03*
X92000Y1254000D03*
X103500Y1229000D03*
X92000Y1241500D03*
X103000Y1244900D03*
X92000Y1214500D03*
X91500Y1229000D03*
X122692Y1257808D03*
X124000Y1247600D03*
X91000Y1272500D03*
X119000Y1269000D03*
X99500Y1310000D03*
Y1294000D03*
X98000Y1282000D03*
X123800Y1283900D03*
X124000Y1270000D03*
X113800Y1287900D03*
X114000Y1274000D03*
X123800Y1311900D03*
X124000Y1298000D03*
X92000Y1295500D03*
X91500Y1314500D03*
X114500Y1296500D03*
X97800Y1327900D03*
X123800Y1337900D03*
X124000Y1324000D03*
X113800Y1331900D03*
X114000Y1318000D03*
X115800Y1363900D03*
X116000Y1350000D03*
X123800Y1365900D03*
X124000Y1352000D03*
X83800Y1365900D03*
X84000Y1352000D03*
X93800Y1353900D03*
X94000Y1340000D03*
Y1366000D03*
X90800Y1331200D03*
X105500Y1415000D03*
X99600Y1416500D03*
X100500Y1384500D03*
Y1389000D03*
X124000Y1376500D03*
X114000Y1376000D03*
X114500Y1370500D03*
X83800Y1391900D03*
X93800Y1379900D03*
Y1393200D03*
X93600Y1407100D03*
X97500Y1412000D03*
X89700Y1409700D03*
X110000Y1418000D03*
X89600Y1464000D03*
X86900Y1451000D03*
X126600Y1461500D03*
X132200Y1424800D03*
X94000Y1427800D03*
X87200Y1431900D03*
X87700Y1446500D03*
X87300Y1436000D03*
X95500Y1468000D03*
X113024Y1452079D03*
X117122Y1448001D03*
X117195Y1456070D03*
X121338Y1452021D03*
X117024Y1452000D03*
X83500Y1469500D03*
X87200Y1440000D03*
X95859Y1448359D03*
X99800Y1455600D03*
X101600Y1431000D03*
X109500Y1438000D03*
X98500Y1428400D03*
X122500Y1437509D03*
X117000Y1435200D03*
X94000Y1514000D03*
X93000Y1518700D03*
X85200Y1515000D03*
X91300Y1488600D03*
X97000Y1503100D03*
X93500Y1482700D03*
X99170Y1485790D03*
X103700Y1470300D03*
X85000Y1490000D03*
X119500Y1501000D03*
X108500Y1501500D03*
X114500Y1501800D03*
X104500Y1506000D03*
X130000Y1501000D03*
X125000Y1500500D03*
X81900Y1510200D03*
X124500Y1524000D03*
X87900Y1523400D03*
X94000Y1562000D03*
Y1550000D03*
X119000Y1529500D03*
X129000Y1562500D03*
X128000Y1568000D03*
X114000Y1546000D03*
X129000Y1542500D03*
X122000Y1546000D03*
Y1538000D03*
X129000Y1549000D03*
X94000Y1556000D03*
X129000Y1535000D03*
X115900Y1569700D03*
X94000Y1568000D03*
X102000D03*
Y1556000D03*
Y1550000D03*
Y1562000D03*
Y1544000D03*
X114000Y1564000D03*
X121800Y1569929D03*
X122000Y1564000D03*
X114000Y1558000D03*
X122000Y1552000D03*
X114000D03*
X122000Y1558000D03*
X111500Y1537500D03*
X129000Y1555500D03*
X108500Y1556500D03*
X116000Y1576000D03*
X122000D03*
Y1584000D03*
X116000D03*
Y1592000D03*
X122000D03*
X116000Y1600000D03*
X122000Y1612000D03*
X104000Y1605500D03*
X116000Y1612000D03*
X122000Y1600000D03*
X128000Y1606000D03*
X94500Y1605500D03*
X113500D03*
X117500Y1669000D03*
X127500D03*
X86000D03*
X97000D03*
X107000D03*
X127000Y1646000D03*
X118000D03*
X117000Y1633500D03*
X127500Y1633000D03*
Y1659500D03*
X117500D03*
X108000Y1646000D03*
X106000Y1634000D03*
X107000Y1659500D03*
X96000Y1646000D03*
X96500Y1634000D03*
X97000Y1659500D03*
X86000Y1646000D03*
Y1634000D03*
Y1659500D03*
X122000Y1685500D03*
X91000Y1685000D03*
X103000D03*
X112500D03*
X98500Y1717000D03*
Y1696500D03*
X99000Y1707000D03*
X117500Y1679000D03*
X125000D03*
X86000D03*
X97500Y1679500D03*
X107500Y1679000D03*
X109500Y1719500D03*
X110000Y1709500D03*
X109500Y1699000D03*
X119500Y1710110D03*
Y1696610D03*
X86500Y1713610D03*
Y1700110D03*
X119500Y1725110D03*
X111500Y1768500D03*
X108500Y1727000D03*
X117500Y1732000D03*
X119500Y1760000D03*
X97500Y1775500D03*
X86500Y1726000D03*
X87000Y1774110D03*
X119500Y1747110D03*
X110500Y1801000D03*
X88500Y1785000D03*
X97500Y1796000D03*
X98000Y1786000D03*
X86500Y1793110D03*
X108268Y1777300D03*
X107768Y1789110D03*
X120000Y1811500D03*
X119500Y1796500D03*
X114000Y1843500D03*
X97000Y1850500D03*
X99500Y1862500D03*
X106500D03*
X114500D03*
X122500D03*
X120500Y1836500D03*
Y1850500D03*
X108500Y1851610D03*
X85100Y1844500D03*
X85700Y1852300D03*
X132000Y1892000D03*
X124500Y1892403D03*
X116948Y1892000D03*
X97500Y1901000D03*
X93000Y1884500D03*
X118000Y1922000D03*
X184000Y55500D03*
X174000D03*
X164000D03*
X154000Y75500D03*
X135000Y50000D03*
Y70000D03*
Y45000D03*
X145000D03*
X155000D03*
X165000D03*
X175000D03*
X137200Y123600D03*
X180500Y112000D03*
X167000Y130500D03*
X176000Y131000D03*
X167000Y93000D03*
X153000Y90500D03*
X171500Y105500D03*
X170500Y120500D03*
X146500Y131859D03*
X154000Y105500D03*
X147600Y150900D03*
X165300Y145200D03*
X137900Y171400D03*
X174500Y143500D03*
X173500Y151500D03*
X138800Y162100D03*
X142000Y291000D03*
X141300Y298100D03*
X143400Y318700D03*
X174000Y316000D03*
X164000D03*
X182000Y296000D03*
X172000D03*
X162000D03*
X172000Y310000D03*
X182000D03*
X184000Y303000D03*
X176000Y302000D03*
X166000D03*
X143300Y343400D03*
X151300Y298200D03*
X154000Y355500D03*
X181800Y369000D03*
X181100Y364050D03*
X180850Y348800D03*
X150000Y386000D03*
X134000Y396000D03*
X150000D03*
X134000Y386000D03*
X161600Y445900D03*
X136000Y447000D03*
X134000Y404500D03*
X174500Y432000D03*
X162000D03*
X145500Y427000D03*
X142000Y432000D03*
X134000Y414000D03*
X150000Y404000D03*
Y414000D03*
X134000Y424000D03*
X150000D03*
X169200Y482800D03*
X144000Y493500D03*
Y486182D03*
X137000Y493000D03*
X136500Y485500D03*
X161900Y451600D03*
X162000Y457600D03*
X161900Y463300D03*
X135500Y454000D03*
Y461000D03*
Y474500D03*
Y468000D03*
X173700Y513900D03*
X144000Y517500D03*
Y501500D03*
X173500Y506000D03*
X173600Y498800D03*
X157100Y500000D03*
X137000Y510000D03*
X137500Y523500D03*
X174900Y523300D03*
X156800Y515400D03*
Y506900D03*
X137000Y501500D03*
X137500Y517500D03*
X144600Y533800D03*
X182600Y546900D03*
X179300Y530000D03*
X184003Y536497D03*
X136500Y597000D03*
X180500Y595000D03*
X171600Y595400D03*
X147500Y551500D03*
X141800Y559250D03*
X150500Y596000D03*
X153500Y574359D03*
X140700Y576600D03*
X152700Y618803D03*
X146000Y641400D03*
X170349Y619949D03*
X166500Y640000D03*
X145500Y604000D03*
X175800Y617635D03*
X164950Y615700D03*
X180500Y627771D03*
X165600Y630269D03*
X137500Y682500D03*
X141800Y676300D03*
X151432Y661741D03*
X148995Y658568D03*
X134100Y674500D03*
X176000Y679000D03*
Y665500D03*
X167300Y653800D03*
X162300Y659100D03*
X183500Y698000D03*
X165500Y677500D03*
X159700Y652000D03*
X152000Y695688D03*
X173500Y740500D03*
X181000Y729000D03*
Y715500D03*
X182500Y745000D03*
X181500Y738500D03*
X169100Y722100D03*
X169000Y795500D03*
X178000Y797500D03*
X175000Y786500D03*
X182500Y758500D03*
X173500Y777500D03*
Y764000D03*
X172000Y757500D03*
X181700Y768400D03*
X165000Y786000D03*
X171500Y819500D03*
X163500Y805500D03*
X177500Y812000D03*
Y826500D03*
X140500Y846500D03*
X134500Y840500D03*
X145500Y885000D03*
X137500Y903000D03*
X146000Y893000D03*
X135000D03*
X134500Y885500D03*
X137500Y876500D03*
X145500Y856500D03*
X157500Y858000D03*
X156300Y877200D03*
X156500Y889000D03*
X153500Y941000D03*
X141000Y938500D03*
X135000Y918000D03*
X135500Y927500D03*
X144000Y919500D03*
Y929000D03*
X143000Y910500D03*
X135500Y909000D03*
X154700Y909700D03*
X154500Y926500D03*
X182000Y950500D03*
X133500Y938000D03*
X134000Y990500D03*
X136500Y967000D03*
X184000Y987500D03*
X135000Y975500D03*
X146800Y1018900D03*
X143900Y1022700D03*
X174000Y1012400D03*
X166300Y1021300D03*
X182500Y1041500D03*
X182000Y1029500D03*
Y1016000D03*
X171000Y1046000D03*
Y1032500D03*
X175000Y1059000D03*
X160500Y1053500D03*
X181000Y1051000D03*
X164700Y1033600D03*
X176000Y1018500D03*
X183500Y1065500D03*
X171000Y1068000D03*
X166000Y1080000D03*
X173000Y1082000D03*
X165000Y1097000D03*
X181000Y1098500D03*
X175000Y1072500D03*
X160500Y1067000D03*
X170000Y1103000D03*
Y1089500D03*
X157000Y1101500D03*
X159500Y1087500D03*
X181000Y1079500D03*
X154600Y1111000D03*
X158500Y1075800D03*
X158595Y1110789D03*
X155000Y1120000D03*
Y1125000D03*
Y1130500D03*
X181000Y1112500D03*
X177102Y1129800D03*
X171502Y1129547D03*
X147500Y1165500D03*
Y1186000D03*
X178644Y1202519D03*
X163344Y1181200D03*
X161500Y1227500D03*
X147500Y1221500D03*
X146500Y1241500D03*
X147000Y1265500D03*
X183500Y1241500D03*
X165000Y1264500D03*
X147500Y1288000D03*
Y1311000D03*
X164500Y1299500D03*
X147500Y1332000D03*
X147000Y1348000D03*
X147500Y1366500D03*
X171000Y1407500D03*
X147000Y1377000D03*
X146500Y1417619D03*
X148300Y1465000D03*
X137000Y1429200D03*
X173375Y1432500D03*
X149686Y1460007D03*
X133500Y1467100D03*
X152500Y1456000D03*
X133799Y1440699D03*
X156000Y1447500D03*
X174000Y1515500D03*
X174500Y1509500D03*
Y1503500D03*
X134000Y1519500D03*
X147500Y1505000D03*
X135000Y1500500D03*
X138500Y1504500D03*
X174000Y1522000D03*
X136000Y1528000D03*
X150000Y1570000D03*
X166898Y1567102D03*
X168500Y1526000D03*
X148000Y1564000D03*
X161300Y1563100D03*
X169500Y1561500D03*
X170000Y1548500D03*
X154000Y1564000D03*
X156000Y1570000D03*
X161400Y1543500D03*
X170000Y1555000D03*
X168500Y1533500D03*
X148000Y1542000D03*
Y1528000D03*
Y1558000D03*
X136000Y1548000D03*
Y1555000D03*
Y1562000D03*
Y1536000D03*
Y1542000D03*
Y1568000D03*
X170000Y1541000D03*
X148000Y1550000D03*
X143518Y1540000D03*
X157000Y1528000D03*
X156000Y1576000D03*
X150000D03*
X156000Y1582000D03*
X156500Y1591000D03*
X150500Y1582000D03*
Y1591000D03*
X172000Y1606000D03*
X182500Y1599400D03*
X146000Y1612000D03*
X148000Y1606000D03*
X182500Y1592000D03*
X164000Y1606000D03*
X156500Y1600000D03*
X156000Y1606000D03*
X150500Y1600000D03*
X138500Y1606000D03*
X182500Y1584500D03*
X141500Y1673000D03*
X176000Y1646000D03*
X166000D03*
X158000D03*
X148000D03*
X176000Y1632000D03*
X178000Y1659500D03*
X167500Y1632500D03*
X170000Y1659500D03*
X149000Y1632500D03*
X159000D03*
X138000Y1634000D03*
X137500Y1659500D03*
X159000D03*
X148500Y1660000D03*
X138000Y1646000D03*
X139000Y1696500D03*
Y1712500D03*
X181500Y1716500D03*
X158500D03*
X167500Y1716000D03*
X182000Y1704000D03*
X168500Y1705000D03*
X158500D03*
X163000Y1697000D03*
X174268Y1697110D03*
X152000D03*
Y1710610D03*
Y1725610D03*
X138500Y1727500D03*
X182000Y1726000D03*
X183600Y1765100D03*
X162500Y1773000D03*
X152500Y1771110D03*
X173268Y1776000D03*
X139000Y1800500D03*
X138000Y1824000D03*
X169000Y1781500D03*
X156500Y1782000D03*
X155500Y1798500D03*
X166500Y1798000D03*
X179000Y1798500D03*
X162000Y1790000D03*
X172768Y1790110D03*
X152000D03*
X144500Y1877000D03*
X139000Y1851000D03*
X138500Y1839500D03*
X161500Y1852500D03*
X183100Y1838300D03*
X160500Y1877500D03*
X173000Y1852610D03*
X151500Y1851110D03*
X161000Y1901500D03*
X194000Y55500D03*
X185000Y45000D03*
X195000D03*
X200000Y55000D03*
Y65000D03*
Y75000D03*
Y85000D03*
X187500Y130500D03*
X190500Y105000D03*
X189500Y120000D03*
X200000Y100000D03*
Y120000D03*
Y140000D03*
X191900Y167700D03*
X191700Y186500D03*
X186000Y143000D03*
X201089Y181700D03*
X197500Y151500D03*
X185500D03*
X191800Y234900D03*
Y221100D03*
X191600Y206900D03*
X201500Y208000D03*
X201000Y222500D03*
X200500Y235000D03*
Y195900D03*
X191900Y244600D03*
X202000Y274000D03*
Y254000D03*
X201089Y282600D03*
X202000Y264000D03*
X187500Y338000D03*
X202000Y340000D03*
Y328000D03*
Y295000D03*
X201089Y305500D03*
Y315500D03*
X184500Y325500D03*
X201500Y378000D03*
X202000Y366500D03*
Y353000D03*
X188500Y364100D03*
X188300Y368600D03*
X192600Y392600D03*
X201089Y388400D03*
X201500Y397500D03*
X200500Y437500D03*
X201000Y430500D03*
X201089Y407000D03*
X200000Y420500D03*
X192471Y397355D03*
X192400Y401900D03*
X186600Y425750D03*
X192300Y410950D03*
X192409Y417655D03*
X186500Y498000D03*
X192000Y490000D03*
Y498000D03*
X200300Y498100D03*
X199500Y489400D03*
X188500Y474500D03*
X189900Y467500D03*
Y460500D03*
X190400Y453500D03*
X195000Y467500D03*
X194500Y474500D03*
X195000Y460500D03*
X195500Y453500D03*
X190239Y447449D03*
X195600Y447500D03*
X192007Y482593D03*
X186500Y513500D03*
Y506000D03*
X192000Y513500D03*
Y506000D03*
X190200Y523400D03*
X201089Y523500D03*
X186500Y519000D03*
X193600Y519100D03*
X200100Y513600D03*
X199800Y506000D03*
X201200Y519200D03*
X201500Y544500D03*
X201089Y529500D03*
X192400Y529400D03*
X191900Y538200D03*
X201500Y535000D03*
X192000Y543500D03*
X202000Y578000D03*
Y586000D03*
Y595000D03*
X193700D03*
X194400Y586000D03*
X201500Y552500D03*
X201089Y558000D03*
X201500Y564000D03*
X201089Y570600D03*
X190500Y550500D03*
X202000Y607500D03*
X196500Y641500D03*
X192600Y633000D03*
X201500Y621500D03*
X202000Y650500D03*
X194000Y628500D03*
Y615000D03*
X192500Y645000D03*
X195000Y670000D03*
X185000Y673500D03*
X188100Y689100D03*
X197500Y685000D03*
X202000Y676500D03*
X192500Y658500D03*
X191500Y692500D03*
X193100Y679000D03*
X184700Y663900D03*
X196000Y718500D03*
X184500Y708500D03*
X197000Y704000D03*
X195500Y739000D03*
X197500Y753000D03*
X202000Y710000D03*
Y740500D03*
X191500Y724000D03*
Y710500D03*
Y746500D03*
X196000Y789500D03*
X196500Y797000D03*
X187900Y785300D03*
X202000Y765000D03*
Y786000D03*
X191500Y760000D03*
X194500Y782500D03*
Y769000D03*
X196800Y828500D03*
X197000Y815000D03*
X190000Y823500D03*
X190500Y831000D03*
X202000Y807500D03*
X201500Y835500D03*
X192500Y853000D03*
Y839500D03*
X185000Y843500D03*
X184500Y879000D03*
Y865500D03*
X192000Y879000D03*
Y865500D03*
X194000Y907000D03*
Y893500D03*
X187000Y891000D03*
X192000Y934500D03*
Y921000D03*
Y948500D03*
X185000Y917500D03*
X192000Y962000D03*
X192500Y985500D03*
Y972000D03*
X195500Y1001000D03*
X190000Y1052000D03*
X195500Y1014500D03*
X193500Y1042500D03*
Y1029000D03*
X195000Y1086500D03*
X194500Y1100500D03*
X195000Y1074500D03*
Y1061000D03*
X201000Y1106500D03*
Y1093000D03*
X187500Y1103500D03*
Y1090000D03*
X191800Y1280900D03*
X194500Y1546000D03*
X193000Y1556500D03*
X197000Y1551500D03*
X195500Y1530500D03*
X193000Y1562500D03*
X189400Y1544100D03*
X187900Y1566600D03*
X189500Y1577000D03*
X198500Y1584000D03*
X192000Y1586000D03*
X197500Y1593000D03*
X191500Y1595000D03*
X199000Y1619500D03*
X190000Y1622000D03*
X198000Y1632500D03*
X191500Y1631000D03*
X198000Y1647500D03*
X196500Y1656000D03*
X197000Y1713000D03*
Y1691500D03*
X184500Y1696500D03*
X197500Y1776500D03*
Y1754000D03*
X197000Y1735500D03*
X185000Y1738500D03*
X198000Y1818500D03*
X196500Y1800500D03*
X185500Y1804500D03*
X186000Y1790000D03*
X197500Y1860000D03*
X197000Y1838500D03*
X194400Y1876700D03*
X185000Y1852500D03*
X201500Y1900500D03*
X190500Y1924000D03*
X201000Y1923000D03*
X195500Y1905000D03*
X196500Y1882000D03*
G54D22*
G01X-430254Y-152763D02*
Y-135263D01*
G01X-421958D02*
X-430254Y-146055D01*
G01X-420648Y-152763D02*
X-426543Y-141097D01*
G01X-412973Y-152763D02*
Y-135263D01*
X-402929Y-152763D01*
Y-135263D01*
G01X-390451Y-152763D02*
X-392198Y-152471D01*
X-393726Y-151305D01*
X-395036Y-149555D01*
X-395910Y-147513D01*
X-396346Y-145180D01*
Y-142846D01*
X-395910Y-140513D01*
X-395036Y-138471D01*
X-393726Y-136722D01*
X-392198Y-135555D01*
X-390451Y-135263D01*
X-388705Y-135555D01*
X-387176Y-136722D01*
X-385866Y-138471D01*
X-384992Y-140513D01*
X-384556Y-142846D01*
Y-145180D01*
X-384992Y-147513D01*
X-385866Y-149555D01*
X-387176Y-151305D01*
X-388705Y-152471D01*
X-390451Y-152763D01*
G01X-377536D02*
X-368366Y-135263D01*
G01X-377536D02*
X-368366Y-152763D01*
G01X-362001Y-158596D02*
X-348901D01*
G01X-342099Y-152763D02*
Y-135263D01*
X-333803D01*
G01X-336859Y-143721D02*
X-342099D01*
G01X-325910Y-152763D02*
X-320451Y-135263D01*
X-314992Y-152763D01*
G01X-316958Y-146638D02*
X-323945D01*
G01X-307973Y-152763D02*
Y-135263D01*
X-297929Y-152763D01*
Y-135263D01*
G01X-263148Y-136722D02*
X-264458Y-135846D01*
X-265986Y-135263D01*
X-267733D01*
X-269698Y-136138D01*
X-271226Y-137596D01*
X-272318Y-139347D01*
X-273191Y-142263D01*
X-273410Y-144888D01*
X-272973Y-147513D01*
X-272318Y-149263D01*
X-271008Y-151013D01*
X-269479Y-152180D01*
X-267951Y-152763D01*
X-266423D01*
X-264894Y-152180D01*
X-263584Y-151305D01*
X-262492Y-150139D01*
G01X-250451Y-152763D02*
X-252198Y-152471D01*
X-253726Y-151305D01*
X-255036Y-149555D01*
X-255910Y-147513D01*
X-256346Y-145180D01*
Y-142846D01*
X-255910Y-140513D01*
X-255036Y-138471D01*
X-253726Y-136722D01*
X-252198Y-135555D01*
X-250451Y-135263D01*
X-248705Y-135555D01*
X-247176Y-136722D01*
X-245866Y-138471D01*
X-244992Y-140513D01*
X-244556Y-142846D01*
Y-145180D01*
X-244992Y-147513D01*
X-245866Y-149555D01*
X-247176Y-151305D01*
X-248705Y-152471D01*
X-250451Y-152763D01*
G01X-237973D02*
Y-135263D01*
X-227929Y-152763D01*
Y-135263D01*
G01X-215451D02*
Y-152763D01*
G01X-220473Y-135263D02*
X-210429D01*
G01X-202318Y-152763D02*
Y-135263D01*
X-196859D01*
X-195113Y-136138D01*
X-194021Y-137305D01*
X-193584Y-139638D01*
X-194021Y-141972D01*
X-195331Y-143430D01*
X-196859Y-144305D01*
X-202318D01*
G01X-196859D02*
X-193584Y-152763D01*
G01X-180451D02*
X-182198Y-152471D01*
X-183726Y-151305D01*
X-185036Y-149555D01*
X-185910Y-147513D01*
X-186346Y-145180D01*
Y-142846D01*
X-185910Y-140513D01*
X-185036Y-138471D01*
X-183726Y-136722D01*
X-182198Y-135555D01*
X-180451Y-135263D01*
X-178705Y-135555D01*
X-177176Y-136722D01*
X-175866Y-138471D01*
X-174992Y-140513D01*
X-174556Y-142846D01*
Y-145180D01*
X-174992Y-147513D01*
X-175866Y-149555D01*
X-177176Y-151305D01*
X-178705Y-152471D01*
X-180451Y-152763D01*
G01X-167318Y-135263D02*
Y-152763D01*
X-158584D01*
G01X-126205Y-143430D02*
X-125331Y-142555D01*
X-124676Y-141097D01*
X-124239Y-139054D01*
X-124676Y-137305D01*
X-125549Y-136138D01*
X-127078Y-135263D01*
X-132973D01*
Y-152763D01*
X-125768D01*
X-124239Y-151597D01*
X-123366Y-149846D01*
X-122929Y-147805D01*
X-123366Y-145763D01*
X-124676Y-144013D01*
X-126205Y-143430D01*
X-132973D01*
G01X-110451Y-152763D02*
X-112198Y-152471D01*
X-113726Y-151305D01*
X-115036Y-149555D01*
X-115910Y-147513D01*
X-116346Y-145180D01*
Y-142846D01*
X-115910Y-140513D01*
X-115036Y-138471D01*
X-113726Y-136722D01*
X-112198Y-135555D01*
X-110451Y-135263D01*
X-108705Y-135555D01*
X-107176Y-136722D01*
X-105866Y-138471D01*
X-104992Y-140513D01*
X-104556Y-142846D01*
Y-145180D01*
X-104992Y-147513D01*
X-105866Y-149555D01*
X-107176Y-151305D01*
X-108705Y-152471D01*
X-110451Y-152763D01*
G01X-98410D02*
X-92951Y-135263D01*
X-87492Y-152763D01*
G01X-89458Y-146638D02*
X-96445D01*
G01X-79818Y-152763D02*
Y-135263D01*
X-74359D01*
X-72613Y-136138D01*
X-71521Y-137305D01*
X-71084Y-139638D01*
X-71521Y-141972D01*
X-72831Y-143430D01*
X-74359Y-144305D01*
X-79818D01*
G01X-74359D02*
X-71084Y-152763D01*
G01X-62754D02*
Y-135263D01*
X-58388D01*
X-56641Y-136138D01*
X-55331Y-137305D01*
X-54239Y-139054D01*
X-53366Y-141097D01*
X-53148Y-144013D01*
X-53366Y-146930D01*
X-54239Y-148972D01*
X-55331Y-150722D01*
X-56641Y-151888D01*
X-58388Y-152763D01*
X-62754D01*
G01X-282378Y-107763D02*
Y-90263D01*
X-276701Y-104846D01*
X-271024Y-90263D01*
Y-107763D01*
G01X-259201D02*
X-260511Y-107471D01*
X-261821Y-106305D01*
X-262695Y-104263D01*
X-263131Y-101930D01*
X-262695Y-99596D01*
X-261821Y-97555D01*
X-260511Y-96388D01*
X-259201Y-96097D01*
X-257891Y-96388D01*
X-256581Y-97555D01*
X-255708Y-99596D01*
X-255489Y-101930D01*
X-255708Y-104263D01*
X-256581Y-106305D01*
X-257891Y-107471D01*
X-259201Y-107763D01*
G01X-237771Y-90263D02*
Y-107763D01*
G01Y-105139D02*
X-238644Y-106597D01*
X-239955Y-107471D01*
X-241483Y-107763D01*
X-243229Y-107180D01*
X-244539Y-105722D01*
X-245413Y-103972D01*
X-245631Y-101930D01*
X-245413Y-99888D01*
X-244539Y-98138D01*
X-243229Y-96680D01*
X-241483Y-96097D01*
X-239955Y-96388D01*
X-238863Y-96972D01*
X-237771Y-98138D01*
G01X-227476Y-99888D02*
X-220489D01*
X-221144Y-97846D01*
X-222236Y-96680D01*
X-223764Y-96097D01*
X-225293Y-96388D01*
X-226603Y-97263D01*
X-227476Y-99305D01*
X-227913Y-101055D01*
Y-102805D01*
X-227476Y-104555D01*
X-226384Y-106305D01*
X-225074Y-107471D01*
X-223546Y-107763D01*
X-222018Y-107180D01*
X-220489Y-105430D01*
G01X-206701Y-107763D02*
Y-90263D01*
G01X-901Y-152763D02*
Y-135263D01*
X-3521Y-138763D01*
G01Y-152763D02*
X1719D01*
G01X12451Y-138180D02*
X13761Y-136430D01*
X15289Y-135555D01*
X17036Y-135263D01*
X19219Y-135846D01*
X20747Y-137305D01*
X21184Y-139054D01*
X20966Y-140805D01*
X20092Y-142263D01*
X15726Y-145180D01*
X13761Y-147221D01*
X12451Y-150139D01*
X12014Y-152763D01*
X21184D01*
G01X36719D02*
Y-135263D01*
X28640Y-147805D01*
X39558D01*
G01X46796Y-149263D02*
X48105Y-151305D01*
X49852Y-152471D01*
X51817Y-152763D01*
X53564Y-152471D01*
X55311Y-151013D01*
X56402Y-149263D01*
X56621Y-147513D01*
X56184Y-145472D01*
X54656Y-144013D01*
X53127Y-143430D01*
X51162D01*
G01X53127D02*
X54437Y-142555D01*
X55529Y-141097D01*
X55966Y-139347D01*
X55529Y-137596D01*
X54437Y-136138D01*
X52472Y-135263D01*
X50507Y-135555D01*
X48542Y-136722D01*
G01X64296Y-149263D02*
X65605Y-151305D01*
X67352Y-152471D01*
X69317Y-152763D01*
X71064Y-152471D01*
X72811Y-151013D01*
X73902Y-149263D01*
X74121Y-147513D01*
X73684Y-145472D01*
X72156Y-144013D01*
X70627Y-143430D01*
X68662D01*
G01X70627D02*
X71937Y-142555D01*
X73029Y-141097D01*
X73466Y-139347D01*
X73029Y-137596D01*
X71937Y-136138D01*
X69972Y-135263D01*
X68007Y-135555D01*
X66042Y-136722D01*
G01X-14018Y-107763D02*
Y-90263D01*
X-8778D01*
X-7031Y-91138D01*
X-5721Y-93180D01*
X-5284Y-95513D01*
X-5721Y-97846D01*
X-6813Y-99596D01*
X-8778Y-100472D01*
X-14018D01*
G01X12652Y-91722D02*
X11342Y-90846D01*
X9814Y-90263D01*
X8067D01*
X6102Y-91138D01*
X4574Y-92596D01*
X3482Y-94347D01*
X2609Y-97263D01*
X2390Y-99888D01*
X2827Y-102513D01*
X3482Y-104263D01*
X4792Y-106013D01*
X6321Y-107180D01*
X7849Y-107763D01*
X9377D01*
X10906Y-107180D01*
X12216Y-106305D01*
X13308Y-105139D01*
G01X27095Y-98430D02*
X27969Y-97555D01*
X28624Y-96097D01*
X29061Y-94054D01*
X28624Y-92305D01*
X27751Y-91138D01*
X26222Y-90263D01*
X20327D01*
Y-107763D01*
X27532D01*
X29061Y-106597D01*
X29934Y-104846D01*
X30371Y-102805D01*
X29934Y-100763D01*
X28624Y-99013D01*
X27095Y-98430D01*
X20327D01*
G01X36299Y-113596D02*
X49399D01*
G01X55327Y-107763D02*
Y-90263D01*
X65371Y-107763D01*
Y-90263D01*
G01X77849Y-107763D02*
X76102Y-107471D01*
X74574Y-106305D01*
X73264Y-104555D01*
X72390Y-102513D01*
X71954Y-100180D01*
Y-97846D01*
X72390Y-95513D01*
X73264Y-93471D01*
X74574Y-91722D01*
X76102Y-90555D01*
X77849Y-90263D01*
X79595Y-90555D01*
X81124Y-91722D01*
X82434Y-93471D01*
X83308Y-95513D01*
X83744Y-97846D01*
Y-100180D01*
X83308Y-102513D01*
X82434Y-104555D01*
X81124Y-106305D01*
X79595Y-107471D01*
X77849Y-107763D01*
G01X128690Y-90263D02*
X134149Y-107763D01*
X139608Y-90263D01*
G01X156016Y-107763D02*
X147282D01*
Y-90263D01*
X156016D01*
G01X152522Y-98721D02*
X147282D01*
G01X164782Y-107763D02*
Y-90263D01*
X170241D01*
X171987Y-91138D01*
X173079Y-92305D01*
X173516Y-94638D01*
X173079Y-96972D01*
X171769Y-98430D01*
X170241Y-99305D01*
X164782D01*
G01X170241D02*
X173516Y-107763D01*
G01X186649Y-108346D02*
X186212Y-108055D01*
Y-107471D01*
X186649Y-107180D01*
X187086Y-107471D01*
Y-108055D01*
X186649Y-108346D01*
G01X151649Y-152763D02*
Y-135263D01*
X149029Y-138763D01*
G01Y-152763D02*
X154269D01*
G01X163472D02*
Y-135263D01*
X169149Y-149846D01*
X174826Y-135263D01*
Y-152763D01*
G01X253482Y-90263D02*
Y-107763D01*
X262216D01*
G01X279279D02*
Y-96097D01*
G01Y-98138D02*
X278406Y-96972D01*
X277095Y-96388D01*
X275567Y-96097D01*
X274039Y-96680D01*
X272729Y-97846D01*
X271855Y-99596D01*
X271419Y-101930D01*
X271855Y-104263D01*
X272729Y-106013D01*
X274039Y-107180D01*
X275567Y-107763D01*
X277095Y-107471D01*
X278406Y-106597D01*
X279279Y-105430D01*
G01X288264Y-113013D02*
X289574Y-113596D01*
X291321Y-113013D01*
X292412Y-111847D01*
X293286Y-110388D01*
X294595Y-105722D01*
X297434Y-96097D01*
G01X290447D02*
X294595Y-105722D01*
G01X307074Y-99888D02*
X314061D01*
X313406Y-97846D01*
X312314Y-96680D01*
X310786Y-96097D01*
X309257Y-96388D01*
X307947Y-97263D01*
X307074Y-99305D01*
X306637Y-101055D01*
Y-102805D01*
X307074Y-104555D01*
X308166Y-106305D01*
X309476Y-107471D01*
X311004Y-107763D01*
X312532Y-107180D01*
X314061Y-105430D01*
G01X324792Y-107763D02*
Y-96097D01*
G01Y-98430D02*
X325884Y-97263D01*
X326976Y-96388D01*
X328504Y-96097D01*
X329595Y-96388D01*
X330906Y-97263D01*
G01X342074Y-105722D02*
X343166Y-106888D01*
X344694Y-107763D01*
X346004D01*
X347314Y-107180D01*
X348187Y-106305D01*
X348624Y-105139D01*
X348406Y-103388D01*
X347532Y-102513D01*
X343602Y-100763D01*
X342729Y-98721D01*
X343166Y-97263D01*
X344039Y-96388D01*
X345349Y-96097D01*
X346659Y-96388D01*
X347969Y-97263D01*
G01X314716Y-135263D02*
Y-152763D01*
X305982D01*
G01X290229D02*
Y-135263D01*
X298308Y-147805D01*
X287390D01*
G01X404346Y-107763D02*
Y-90263D01*
X408712D01*
X410459Y-91138D01*
X411769Y-92305D01*
X412861Y-94054D01*
X413734Y-96097D01*
X413952Y-99013D01*
X413734Y-101930D01*
X412861Y-103972D01*
X411769Y-105722D01*
X410459Y-106888D01*
X408712Y-107763D01*
X404346D01*
G01X423374Y-99888D02*
X430361D01*
X429706Y-97846D01*
X428614Y-96680D01*
X427086Y-96097D01*
X425557Y-96388D01*
X424247Y-97263D01*
X423374Y-99305D01*
X422937Y-101055D01*
Y-102805D01*
X423374Y-104555D01*
X424466Y-106305D01*
X425776Y-107471D01*
X427304Y-107763D01*
X428832Y-107180D01*
X430361Y-105430D01*
G01X440874Y-105722D02*
X441966Y-106888D01*
X443494Y-107763D01*
X444804D01*
X446114Y-107180D01*
X446987Y-106305D01*
X447424Y-105139D01*
X447206Y-103388D01*
X446332Y-102513D01*
X442402Y-100763D01*
X441529Y-98721D01*
X441966Y-97263D01*
X442839Y-96388D01*
X444149Y-96097D01*
X445459Y-96388D01*
X446769Y-97263D01*
G01X461649Y-96097D02*
Y-107763D01*
G01Y-91430D02*
X461212Y-91138D01*
Y-90555D01*
X461649Y-90263D01*
X462086Y-90555D01*
Y-91138D01*
X461649Y-91430D01*
G01X476092Y-112138D02*
X477621Y-113305D01*
X479367Y-113596D01*
X480895Y-113305D01*
X482206Y-111847D01*
X483079Y-109805D01*
Y-96097D01*
G01Y-98430D02*
X482206Y-97263D01*
X480895Y-96388D01*
X479367Y-96097D01*
X477621Y-96680D01*
X476529Y-97846D01*
X475655Y-99888D01*
X475219Y-101930D01*
X475437Y-103680D01*
X476311Y-105722D01*
X477621Y-107180D01*
X479367Y-107763D01*
X480677Y-107471D01*
X482206Y-106305D01*
X483079Y-105139D01*
G01X492937Y-107763D02*
Y-96097D01*
G01Y-99013D02*
X493811Y-97555D01*
X495121Y-96388D01*
X496867Y-96097D01*
X498395Y-96388D01*
X499706Y-97555D01*
X500361Y-99596D01*
Y-107763D01*
G01X510874Y-99888D02*
X517861D01*
X517206Y-97846D01*
X516114Y-96680D01*
X514586Y-96097D01*
X513057Y-96388D01*
X511747Y-97263D01*
X510874Y-99305D01*
X510437Y-101055D01*
Y-102805D01*
X510874Y-104555D01*
X511966Y-106305D01*
X513276Y-107471D01*
X514804Y-107763D01*
X516332Y-107180D01*
X517861Y-105430D01*
G01X528592Y-107763D02*
Y-96097D01*
G01Y-98430D02*
X529684Y-97263D01*
X530776Y-96388D01*
X532304Y-96097D01*
X533395Y-96388D01*
X534706Y-97263D01*
G01X448096Y-152763D02*
Y-135263D01*
X452462D01*
X454209Y-136138D01*
X455519Y-137305D01*
X456611Y-139054D01*
X457484Y-141097D01*
X457702Y-144013D01*
X457484Y-146930D01*
X456611Y-148972D01*
X455519Y-150722D01*
X454209Y-151888D01*
X452462Y-152763D01*
X448096D01*
G01X470399Y-141097D02*
Y-152763D01*
G01Y-136430D02*
X469962Y-136138D01*
Y-135555D01*
X470399Y-135263D01*
X470836Y-135555D01*
Y-136138D01*
X470399Y-136430D01*
G01X487899Y-152763D02*
X486589Y-152471D01*
X485279Y-151305D01*
X484405Y-149263D01*
X483969Y-146930D01*
X484405Y-144596D01*
X485279Y-142555D01*
X486589Y-141388D01*
X487899Y-141097D01*
X489209Y-141388D01*
X490519Y-142555D01*
X491392Y-144596D01*
X491611Y-146930D01*
X491392Y-149263D01*
X490519Y-151305D01*
X489209Y-152471D01*
X487899Y-152763D01*
G01X575349D02*
Y-135263D01*
X572729Y-138763D01*
G01Y-152763D02*
X577969D01*
G01X588701Y-138180D02*
X590011Y-136430D01*
X591539Y-135555D01*
X593286Y-135263D01*
X595469Y-135846D01*
X596997Y-137305D01*
X597434Y-139054D01*
X597216Y-140805D01*
X596342Y-142263D01*
X591976Y-145180D01*
X590011Y-147221D01*
X588701Y-150139D01*
X588264Y-152763D01*
X597434D01*
G01X606419Y-153346D02*
X614279Y-135263D01*
G01X627849D02*
X626102Y-135846D01*
X624792Y-137305D01*
X623919Y-139054D01*
X623264Y-141388D01*
X623046Y-144013D01*
X623264Y-146638D01*
X623919Y-148972D01*
X624792Y-150722D01*
X626102Y-152180D01*
X627849Y-152763D01*
X629595Y-152180D01*
X630906Y-150722D01*
X631779Y-148972D01*
X632434Y-146638D01*
X632652Y-144013D01*
X632434Y-141388D01*
X631779Y-139054D01*
X630906Y-137305D01*
X629595Y-135846D01*
X627849Y-135263D01*
G01X644912Y-152763D02*
X645349Y-148972D01*
X646004Y-145763D01*
X646877Y-142846D01*
X647969Y-139638D01*
X649716Y-135263D01*
X640982D01*
G01X658919Y-153346D02*
X666779Y-135263D01*
G01X676201Y-138180D02*
X677511Y-136430D01*
X679039Y-135555D01*
X680786Y-135263D01*
X682969Y-135846D01*
X684497Y-137305D01*
X684934Y-139054D01*
X684716Y-140805D01*
X683842Y-142263D01*
X679476Y-145180D01*
X677511Y-147221D01*
X676201Y-150139D01*
X675764Y-152763D01*
X684934D01*
G01X697849Y-135263D02*
X696102Y-135846D01*
X694792Y-137305D01*
X693919Y-139054D01*
X693264Y-141388D01*
X693046Y-144013D01*
X693264Y-146638D01*
X693919Y-148972D01*
X694792Y-150722D01*
X696102Y-152180D01*
X697849Y-152763D01*
X699595Y-152180D01*
X700906Y-150722D01*
X701779Y-148972D01*
X702434Y-146638D01*
X702652Y-144013D01*
X702434Y-141388D01*
X701779Y-139054D01*
X700906Y-137305D01*
X699595Y-135846D01*
X697849Y-135263D01*
G01X715349Y-152763D02*
Y-135263D01*
X712729Y-138763D01*
G01Y-152763D02*
X717969D01*
G01X728701Y-138180D02*
X730011Y-136430D01*
X731539Y-135555D01*
X733286Y-135263D01*
X735469Y-135846D01*
X736997Y-137305D01*
X737434Y-139054D01*
X737216Y-140805D01*
X736342Y-142263D01*
X731976Y-145180D01*
X730011Y-147221D01*
X728701Y-150139D01*
X728264Y-152763D01*
X737434D01*
G01X623046Y-107763D02*
Y-90263D01*
X627412D01*
X629159Y-91138D01*
X630469Y-92305D01*
X631561Y-94054D01*
X632434Y-96097D01*
X632652Y-99013D01*
X632434Y-101930D01*
X631561Y-103972D01*
X630469Y-105722D01*
X629159Y-106888D01*
X627412Y-107763D01*
X623046D01*
G01X649279D02*
Y-96097D01*
G01Y-98138D02*
X648406Y-96972D01*
X647095Y-96388D01*
X645567Y-96097D01*
X644039Y-96680D01*
X642729Y-97846D01*
X641855Y-99596D01*
X641419Y-101930D01*
X641855Y-104263D01*
X642729Y-106013D01*
X644039Y-107180D01*
X645567Y-107763D01*
X647095Y-107471D01*
X648406Y-106597D01*
X649279Y-105430D01*
G01X662849Y-90263D02*
Y-107763D01*
G01X659792Y-96097D02*
X665906D01*
G01X677074Y-99888D02*
X684061D01*
X683406Y-97846D01*
X682314Y-96680D01*
X680786Y-96097D01*
X679257Y-96388D01*
X677947Y-97263D01*
X677074Y-99305D01*
X676637Y-101055D01*
Y-102805D01*
X677074Y-104555D01*
X678166Y-106305D01*
X679476Y-107471D01*
X681004Y-107763D01*
X682532Y-107180D01*
X684061Y-105430D01*
G54D13*
X15906Y48110D03*
Y58110D03*
Y68110D03*
Y78110D03*
Y88110D03*
Y481339D03*
Y491339D03*
Y501339D03*
Y511339D03*
Y521339D03*
Y741181D03*
Y751181D03*
Y761181D03*
Y771181D03*
Y781181D03*
Y1187323D03*
Y1197323D03*
Y1207323D03*
Y1217323D03*
Y1227323D03*
Y1447165D03*
Y1457165D03*
Y1467165D03*
Y1477165D03*
Y1487165D03*
Y1880394D03*
Y1890394D03*
Y1900394D03*
Y1910394D03*
Y1920394D03*
X128937Y1778819D03*
X118937D03*
X165000Y1390500D03*
Y1380500D03*
Y1370500D03*
X138937Y1778819D03*
G54D23*
G01X43388Y694286D02*
Y691964D01*
X10581Y659157D01*
Y469245D01*
X10579Y469243D01*
Y447332D01*
X10581Y447330D01*
Y318419D01*
X17500Y311500D01*
Y240033D01*
X31533Y226000D01*
X33272D01*
X36324Y222948D01*
Y207424D01*
X34475Y205575D01*
Y180325D01*
X39300Y175500D01*
G01X46500Y705500D02*
Y702000D01*
X48575Y699925D01*
Y595575D01*
X29475Y576475D01*
Y568975D01*
X19596Y559096D01*
Y531404D01*
X23431Y527569D01*
Y479620D01*
X12329Y468518D01*
Y448057D01*
X14196Y446190D01*
Y325458D01*
X19300Y320354D01*
Y273054D01*
X22100Y270254D01*
Y245500D01*
X38000Y229600D01*
Y228500D01*
G01X32425Y177900D02*
Y206024D01*
X32763Y206362D01*
Y206363D01*
X34574Y208174D01*
Y222223D01*
X32597Y224200D01*
X30858D01*
X15700Y239358D01*
Y310754D01*
X8831Y317623D01*
Y446605D01*
X8829Y446607D01*
Y469968D01*
X8831Y469970D01*
Y659883D01*
X9855Y660907D01*
X9856D01*
X41224Y692275D01*
Y694774D01*
X43950Y697500D01*
X44500D01*
G01X41100Y231000D02*
X23900Y248200D01*
Y271000D01*
X21100Y273800D01*
Y321100D01*
X15946Y326254D01*
Y446915D01*
X14079Y448782D01*
Y467793D01*
X25181Y478895D01*
Y528319D01*
X21346Y532154D01*
Y558346D01*
X31500Y568500D01*
Y575500D01*
X50325Y594325D01*
Y702675D01*
X49500Y703500D01*
G01X31299Y358563D02*
X32475Y359739D01*
Y442525D01*
X21229Y453771D01*
Y463329D01*
X32800Y474900D01*
Y526100D01*
X45000Y538300D01*
Y576500D01*
X66500Y598000D01*
Y612500D01*
X71775Y617775D01*
Y663919D01*
X69500Y666194D01*
Y678049D01*
X64725Y682824D01*
Y843275D01*
X57809Y850191D01*
Y852500D01*
G01X18035Y572076D02*
X12331Y566372D01*
Y484914D01*
X15906Y481339D01*
G01X25148Y570800D02*
X15646Y561298D01*
Y529354D01*
X19481Y525519D01*
Y504914D01*
X15906Y501339D01*
G01X23450Y577491D02*
X18035Y572076D01*
G01X19200Y1707000D02*
X21425Y1704775D01*
Y1641125D01*
X17846Y1637546D01*
Y1495869D01*
X25181Y1488534D01*
Y1434281D01*
X21346Y1430446D01*
Y1389154D01*
X78988Y1331512D01*
Y1156288D01*
X76117Y1153417D01*
Y1143963D01*
X82500Y1137580D01*
Y1125500D01*
X125300Y1082700D01*
Y1006700D01*
X143000Y989000D01*
Y953032D01*
G01X19250Y1663100D02*
Y1641425D01*
X16096Y1638271D01*
Y1495144D01*
X23431Y1487809D01*
Y1435137D01*
X19596Y1431302D01*
Y1388404D01*
X77238Y1330762D01*
Y1157038D01*
X74367Y1154167D01*
Y1142633D01*
X80500Y1136500D01*
Y1125000D01*
X122900Y1082600D01*
Y1007400D01*
G01X15906Y1447165D02*
X13896Y1445155D01*
Y1384604D01*
X30438Y1368062D01*
Y1367562D01*
G01X15906Y1467165D02*
X19481Y1463590D01*
Y1438181D01*
X15646Y1434346D01*
Y1385554D01*
X73163Y1328037D01*
Y1158780D01*
G01X137500Y682500D02*
X137875Y682875D01*
Y830375D01*
X154100Y846600D01*
X154200D01*
X154400Y846800D01*
Y846900D01*
X160300Y852800D01*
Y965100D01*
X157100Y968300D01*
Y983100D01*
X131749Y1008451D01*
Y1017300D01*
X130401Y1018648D01*
Y1073209D01*
X130400Y1073210D01*
Y1082600D01*
X86500Y1126500D01*
Y1143000D01*
X80900Y1148600D01*
Y1332100D01*
X36700Y1376300D01*
Y1410100D01*
X38496Y1411896D01*
Y1430300D01*
X27575Y1441221D01*
Y1488615D01*
X19596Y1496594D01*
Y1636095D01*
X23200Y1639699D01*
Y1762000D01*
X25000Y1763800D01*
G01X45300Y1776300D02*
X38300Y1769300D01*
X36500D01*
X24951Y1757751D01*
Y1637949D01*
X21346Y1634344D01*
Y1498254D01*
X29325Y1490275D01*
Y1442052D01*
X40246Y1431131D01*
Y1412754D01*
X42200Y1410800D01*
Y1374000D01*
X83500Y1332700D01*
Y1149500D01*
X88500Y1144500D01*
Y1127300D01*
X132150Y1083650D01*
Y1073935D01*
X132151Y1073934D01*
Y1019849D01*
X133900Y1018100D01*
Y1009000D01*
X159100Y983800D01*
Y970200D01*
X162050Y967250D01*
Y851975D01*
X154875Y844800D01*
X154870D01*
X140219Y830149D01*
Y685081D01*
X141800Y683500D01*
Y676300D01*
G01X78400Y86100D02*
X84500Y80000D01*
Y69253D01*
X88253Y65500D01*
G01X122500Y653650D02*
X76800Y607950D01*
Y594649D01*
X65451Y583300D01*
X62648D01*
X60900Y581552D01*
Y572900D01*
X50350Y562350D01*
Y536050D01*
X38250Y523950D01*
Y488426D01*
X38249Y488425D01*
Y486976D01*
X43146Y482079D01*
Y444598D01*
X38148Y439600D01*
Y433800D01*
X38149Y433799D01*
Y428772D01*
X38150Y428771D01*
Y363522D01*
X39950Y361722D01*
Y268751D01*
X54375Y254326D01*
Y231075D01*
X51925Y228625D01*
Y215875D01*
X56075Y211725D01*
Y206027D01*
X51525Y201477D01*
Y190523D01*
X57600Y184448D01*
Y184447D01*
X57601Y184446D01*
Y106799D01*
X78300Y86100D01*
X78400D01*
G01X81500Y75500D02*
Y78400D01*
X58749Y101151D01*
G01D02*
X55851Y104049D01*
Y183721D01*
X49775Y189797D01*
Y205175D01*
X51575Y206975D01*
Y211677D01*
X49825Y213427D01*
Y237077D01*
X50375Y237627D01*
Y255825D01*
X38200Y268000D01*
Y360997D01*
X36400Y362797D01*
Y362799D01*
X36399Y362800D01*
Y433074D01*
X36398Y433075D01*
Y440325D01*
X36399Y440326D01*
Y440399D01*
X41396Y445396D01*
Y481353D01*
X36498Y486251D01*
Y487701D01*
X36499Y487702D01*
Y489150D01*
X36500Y489151D01*
Y524800D01*
X48600Y536900D01*
Y563100D01*
X59100Y573600D01*
Y582227D01*
X61973Y585100D01*
X64776D01*
X75000Y595324D01*
Y609624D01*
X117400Y652024D01*
Y653100D01*
G01X149606Y204409D02*
X143709D01*
X115300Y176000D01*
X89693D01*
X84400Y170707D01*
Y170453D01*
X82211Y168264D01*
X81957D01*
X75300Y161607D01*
Y155300D01*
G01X49924Y153261D02*
Y166376D01*
X47800Y168500D01*
Y183800D01*
X43375Y188225D01*
Y203875D01*
X47395Y207895D01*
Y240000D01*
X38800Y248595D01*
Y264900D01*
X36400Y267300D01*
Y360000D01*
X34649Y361751D01*
Y432349D01*
X34648Y432350D01*
Y441050D01*
X34649Y441051D01*
Y441849D01*
X39646Y446846D01*
Y480628D01*
X34748Y485526D01*
Y488426D01*
X34749Y488427D01*
Y489876D01*
X34750Y489877D01*
Y525550D01*
X46850Y537650D01*
Y575150D01*
X68400Y596700D01*
Y611900D01*
X100600Y644100D01*
Y656600D01*
G01X53400Y191300D02*
X54175Y192075D01*
X72825D01*
X78386Y186514D01*
X83014D01*
X84764Y188264D01*
X114264D01*
X143300Y217300D01*
Y225700D01*
X147300Y229700D01*
X162130D01*
X163800Y231370D01*
Y257200D01*
X168904Y262304D01*
X180904D01*
X192300Y273700D01*
Y388600D01*
X189800Y391100D01*
Y421500D01*
X194400Y426100D01*
Y439900D01*
X185200Y449100D01*
Y449200D01*
X182300Y452100D01*
Y531000D01*
X169000Y544300D01*
X168999D01*
X149500Y563799D01*
Y586800D01*
X177975Y615275D01*
Y619625D01*
X169800Y627800D01*
Y682500D01*
X161500Y690800D01*
Y691700D01*
G01X41100Y231000D02*
Y207200D01*
X39425Y205525D01*
Y185475D01*
X43700Y181200D01*
G01X43400Y174325D02*
X43175D01*
X36245Y181255D01*
Y204845D01*
X38400Y207000D01*
Y228100D01*
X38000Y228500D01*
G01X52700Y162300D02*
Y166200D01*
X49600Y169300D01*
Y184500D01*
X45125Y188975D01*
Y203125D01*
X49700Y207700D01*
Y209700D01*
G01X169606Y224409D02*
X169605D01*
X164600Y219404D01*
Y212900D01*
X162484Y210784D01*
X145000D01*
X112216Y178000D01*
X84500D01*
X83014Y176514D01*
X78482D01*
X71596Y183400D01*
X64400D01*
G01X47800Y199200D02*
X48000Y199000D01*
Y188600D01*
X52500Y184100D01*
Y175200D01*
G01X64000Y199700D02*
X67771D01*
X79207Y188264D01*
X82211D01*
X84400Y190453D01*
Y190707D01*
X90093Y196400D01*
X100302D01*
X107000Y203098D01*
Y210700D01*
X110709Y214409D01*
G01X192007Y482593D02*
X198500Y476100D01*
Y444800D01*
X196575Y442875D01*
Y422675D01*
X194775Y420875D01*
Y272075D01*
X183254Y260554D01*
X178103D01*
X175980Y258431D01*
Y257180D01*
X165800Y247000D01*
Y224500D01*
X160334Y219034D01*
X149034D01*
X116500Y186500D01*
X90193D01*
X84400Y180707D01*
Y180453D01*
X82211Y178264D01*
X79207D01*
X70500Y186971D01*
Y190200D01*
G01X90709Y234409D02*
X85334Y239784D01*
X74416D01*
X65874Y248326D01*
Y254751D01*
X50074Y270551D01*
Y282400D01*
X46950Y285524D01*
Y364624D01*
X46175Y365399D01*
X46174D01*
X45150Y366423D01*
Y431672D01*
X45149Y431673D01*
Y436700D01*
X50200Y441751D01*
Y482050D01*
X59100Y490950D01*
Y560424D01*
X71975Y573299D01*
Y574623D01*
X80300Y582948D01*
Y587700D01*
X84100Y591500D01*
Y605173D01*
X129625Y650698D01*
Y657375D01*
X121500Y665500D01*
Y683500D01*
G01X119576Y687008D02*
X116825Y684257D01*
Y667675D01*
X127875Y656625D01*
Y651423D01*
X82200Y605748D01*
Y592100D01*
X66400Y576300D01*
Y570400D01*
X57350Y561350D01*
Y491675D01*
X48450Y482775D01*
Y442477D01*
X43398Y437425D01*
Y435975D01*
X43399Y435974D01*
Y430948D01*
X43400Y430947D01*
Y365698D01*
X45200Y363898D01*
Y283824D01*
X48324Y280700D01*
Y265676D01*
X56900Y257100D01*
Y253247D01*
X67475Y242672D01*
Y216473D01*
X79539Y204409D01*
X80709D01*
G01X71400Y208150D02*
X78766Y200784D01*
X82211D01*
X87000Y205573D01*
Y215827D01*
X90073Y218900D01*
X92802D01*
X96200Y222298D01*
Y225027D01*
X99207Y228034D01*
X107084D01*
X110709Y224409D01*
G01X69900Y236600D02*
X70500Y236000D01*
X73252D01*
X77900Y231352D01*
Y229034D01*
G01X117600Y234900D02*
X114466Y238034D01*
X99207D01*
X97000Y235827D01*
Y235573D01*
X91627Y230200D01*
X91373D01*
X86200Y225027D01*
Y222298D01*
X82002Y218100D01*
X71100D01*
X70600Y217600D01*
G01X74800Y231800D02*
Y231500D01*
X69400Y226100D01*
G01X61300Y229400D02*
Y215598D01*
X77864Y199034D01*
X83034D01*
X84784Y200784D01*
X97084D01*
X100709Y204409D01*
G01X122100Y230100D02*
X122000Y230000D01*
X98698D01*
X94400Y225702D01*
Y222973D01*
X92127Y220700D01*
X89398D01*
X84400Y215702D01*
Y212973D01*
X82211Y210784D01*
X75816D01*
X75300Y211300D01*
G01X85676Y231100D02*
X84400Y229824D01*
Y222973D01*
X82211Y220784D01*
X73016D01*
X72100Y221700D01*
G01X53500Y199700D02*
X55375Y201575D01*
X68371D01*
X72646Y197300D01*
X77600D01*
X77616Y197284D01*
X83784D01*
X84700Y198200D01*
X99627D01*
X104334Y202907D01*
Y220784D01*
X100709Y224409D01*
G01X60300Y275700D02*
Y288300D01*
X54550Y294050D01*
Y367775D01*
X52750Y369575D01*
Y433550D01*
X59104Y439904D01*
Y441094D01*
G01X57500Y268500D02*
X57650Y268650D01*
Y288050D01*
X52500Y293200D01*
Y366925D01*
X50700Y368725D01*
Y434400D01*
X55750Y439450D01*
Y479750D01*
X64650Y488650D01*
Y539950D01*
X76166Y551466D01*
G01X120702Y690847D02*
X123675Y687874D01*
Y665825D01*
X131375Y658125D01*
Y649973D01*
X86705Y605303D01*
Y593995D01*
X88875Y591825D01*
Y590223D01*
X82100Y583448D01*
Y575800D01*
X60850Y554550D01*
Y490225D01*
X51950Y481325D01*
Y441026D01*
X46899Y435975D01*
Y434525D01*
X46900Y434524D01*
Y367149D01*
X47924Y366125D01*
X47925D01*
X48700Y365350D01*
Y287225D01*
X51825Y284100D01*
Y271275D01*
X67625Y255475D01*
Y249974D01*
X69574Y248025D01*
X79198D01*
X79207Y248034D01*
X82211D01*
X84334Y245911D01*
Y245657D01*
X90191Y239800D01*
X139300D01*
X140900Y238200D01*
X155815D01*
X159606Y234409D01*
G01X128600Y669500D02*
Y663400D01*
X133125Y658875D01*
Y649248D01*
X88455Y604578D01*
Y598197D01*
X90875Y595777D01*
Y581075D01*
X87000Y577200D01*
Y566800D01*
X62600Y542400D01*
Y489500D01*
X53700Y480600D01*
Y440300D01*
X48650Y435250D01*
Y367875D01*
X50450Y366075D01*
Y290250D01*
X54800Y285900D01*
Y276400D01*
X54000Y275600D01*
G01X45800Y277800D02*
X43450Y280150D01*
Y363173D01*
X41650Y364973D01*
Y430221D01*
X41649Y430222D01*
Y435249D01*
X41648Y435250D01*
Y438150D01*
X46700Y443202D01*
Y483500D01*
X55600Y492400D01*
Y562100D01*
X64600Y571100D01*
Y577400D01*
X80400Y593200D01*
Y606423D01*
X126125Y652148D01*
Y655375D01*
X118127Y663373D01*
Y663400D01*
G01X114000Y663350D02*
X116599Y660751D01*
X118051D01*
X124375Y654427D01*
Y652873D01*
X78600Y607098D01*
Y593900D01*
X62800Y578100D01*
Y571800D01*
X53000Y562000D01*
Y536181D01*
X40000Y523181D01*
Y487700D01*
X44950Y482750D01*
Y443927D01*
X39898Y438875D01*
Y434525D01*
X39899Y434524D01*
Y429497D01*
X39900Y429496D01*
Y364247D01*
X40924Y363223D01*
X40925D01*
X41700Y362448D01*
Y274000D01*
X43400Y272300D01*
G01X59104Y441094D02*
X57800Y442398D01*
Y478900D01*
X66800Y487900D01*
Y537700D01*
X128550Y599450D01*
X144026D01*
X158724Y614148D01*
Y625313D01*
X153350Y630687D01*
Y659823D01*
X151432Y661741D01*
G01X148995Y658568D02*
X151300Y656263D01*
Y629837D01*
X156674Y624463D01*
Y617902D01*
X144947Y606175D01*
X132375D01*
X127800Y601600D01*
X127700D01*
X118400Y592300D01*
Y592200D01*
X90800Y564600D01*
X89300D01*
X76166Y551466D01*
G01X82900Y620600D02*
X82400D01*
X73200Y611400D01*
Y596600D01*
X72500Y595900D01*
G01X56800Y576950D02*
Y582600D01*
X70300Y596100D01*
Y611200D01*
X106400Y647300D01*
Y648300D01*
G01X67302Y1133490D02*
X72675Y1128117D01*
Y825875D01*
X70525Y823725D01*
Y764225D01*
X80369Y754381D01*
Y697058D01*
X79271Y695960D01*
X76383D01*
X72475Y692052D01*
Y684998D01*
X79000Y678473D01*
Y675500D01*
G01X80900Y668400D02*
Y673600D01*
X79000Y675500D01*
G01X86443Y662853D02*
X86296Y663000D01*
X80749D01*
X76950Y666799D01*
Y669950D01*
X73500Y673400D01*
Y679000D01*
X68975Y683525D01*
Y693503D01*
X75375Y699903D01*
Y753475D01*
X67025Y761825D01*
Y826325D01*
X69175Y828475D01*
Y901225D01*
X63800Y906600D01*
Y917100D01*
X54200Y926700D01*
G01X73000Y728000D02*
Y727400D01*
X66925Y721325D01*
Y683100D01*
X71250Y678775D01*
Y669172D01*
X80673Y659749D01*
X83900D01*
G01X84504Y666353D02*
X84376Y666225D01*
X79999D01*
X78725Y667499D01*
Y670775D01*
X75250Y674250D01*
Y679748D01*
X70725Y684273D01*
Y692778D01*
X77125Y699178D01*
Y754275D01*
X68775Y762625D01*
Y824575D01*
X70925Y826725D01*
Y903375D01*
X67000Y907300D01*
G01X84000Y674000D02*
X81950Y676050D01*
Y677998D01*
X74225Y685723D01*
Y691150D01*
X75571Y692496D01*
G01X60900Y670200D02*
X60500Y670600D01*
Y674700D01*
G01D02*
Y682540D01*
G01X76100Y686900D02*
X77500D01*
X80479Y683921D01*
G01D02*
X83850Y680550D01*
Y678109D01*
G01X72400Y822900D02*
Y766025D01*
X82925Y755500D01*
Y691967D01*
X86597Y688295D01*
Y681103D01*
G01X56000Y885500D02*
Y882448D01*
X57809Y880639D01*
Y852500D01*
G01X54000Y996500D02*
X53000Y995500D01*
Y927900D01*
X54200Y926700D01*
G01X67000Y907300D02*
Y1013152D01*
X54652Y1025500D01*
X53500D01*
G01X37700Y991600D02*
X37500Y991800D01*
Y998000D01*
G01D02*
Y1099823D01*
G01X78292Y1148041D02*
X84500Y1141833D01*
Y1126000D01*
X128650Y1081850D01*
Y1072485D01*
X128651Y1072484D01*
Y1017449D01*
X129500Y1016600D01*
Y1008100D01*
X153125Y984475D01*
Y963875D01*
X156500Y960500D01*
Y947077D01*
X151325Y941902D01*
Y846325D01*
X135325Y830325D01*
Y681568D01*
X132110Y678353D01*
G01X70500Y1161500D02*
Y1168948D01*
X69225Y1170223D01*
Y1176431D01*
X70775Y1177981D01*
Y1327225D01*
X30438Y1367562D01*
G01X147900Y588100D02*
X147600Y587800D01*
Y557100D01*
X151200Y553500D01*
Y452000D01*
X137000Y437800D01*
Y427600D01*
X141400Y423200D01*
Y383600D01*
X135800Y378000D01*
Y246200D01*
X131400Y241800D01*
X120000D01*
X112700Y249100D01*
X105400D01*
X102700Y246400D01*
Y246300D01*
X102600D01*
X100709Y244409D01*
G01X115300Y551800D02*
X116624D01*
X146175Y522249D01*
Y454099D01*
X136901Y444825D01*
X135824D01*
X127200Y436201D01*
Y246000D01*
G01X90630Y602020D02*
X97625Y595025D01*
X116975D01*
X140753Y618803D01*
X152700D01*
G01X136500Y597000D02*
X129000D01*
G01X122692Y1257808D02*
X126500Y1254000D01*
Y1095500D01*
X135651Y1086349D01*
Y1080358D01*
X135650Y1080357D01*
Y1075385D01*
X135651Y1075384D01*
Y1021749D01*
X137500Y1019900D01*
Y1011000D01*
X160800Y987700D01*
X163600D01*
X165800Y985500D01*
Y850750D01*
X156250Y841200D01*
X156220D01*
X143719Y828699D01*
Y687306D01*
X145725Y685300D01*
Y671225D01*
X140773Y666273D01*
Y664627D01*
X142825Y662575D01*
Y623725D01*
X116000Y596900D01*
G01X131135Y639554D02*
X134875Y643294D01*
Y659625D01*
X130894Y663606D01*
Y677094D01*
X132110Y678310D01*
Y678353D01*
G01X112800Y653500D02*
Y650600D01*
X82900Y620700D01*
Y620600D01*
G01X108200Y655825D02*
Y650000D01*
X106500Y648300D01*
X106400D01*
G01X124000Y1247600D02*
Y1094500D01*
X133901Y1084599D01*
Y1081083D01*
X133900Y1081082D01*
Y1074660D01*
X133901Y1074659D01*
Y1020954D01*
X135655Y1019200D01*
Y1009845D01*
X160900Y984600D01*
Y971600D01*
X163900Y968600D01*
Y851325D01*
X155575Y843000D01*
X155545D01*
X141969Y829424D01*
Y686131D01*
X143975Y684125D01*
Y672351D01*
X139023Y667399D01*
Y663877D01*
X141075Y661825D01*
Y626783D01*
X113655Y599363D01*
G01X88967Y659749D02*
X83900D01*
G01X84000Y674000D02*
Y672400D01*
X90674Y665726D01*
Y663367D01*
G01X100600Y656600D02*
X102500Y658500D01*
Y668700D01*
X100600Y670600D01*
G01X128600Y669500D02*
Y677920D01*
X133575Y682895D01*
Y831075D01*
X149375Y846875D01*
Y942427D01*
X154750Y947802D01*
Y956425D01*
X150500Y960675D01*
Y976500D01*
G01X100200Y663900D02*
X99849D01*
X92849Y670900D01*
Y674851D01*
X86597Y681103D01*
G01X115217Y765517D02*
X111625Y761925D01*
Y700675D01*
X113200Y699100D01*
Y668327D01*
X118127Y663400D01*
G01X111100Y788200D02*
Y783200D01*
X107875Y779975D01*
Y737100D01*
X107873Y737098D01*
Y709779D01*
X107875Y709777D01*
Y708223D01*
X107873Y708221D01*
Y697976D01*
X106323Y696426D01*
Y679177D01*
X109288Y676212D01*
Y673099D01*
X109287Y673098D01*
Y666172D01*
X109005Y665890D01*
G01X116402Y779402D02*
X109875Y772875D01*
Y699925D01*
X111400Y698400D01*
Y665950D01*
X114000Y663350D01*
G01X107164Y862285D02*
X108954Y864075D01*
X114177D01*
X126675Y851577D01*
Y776975D01*
X115217Y765517D01*
G01X106404Y840700D02*
X108154D01*
X116875Y831979D01*
Y822575D01*
X111100Y816800D01*
Y788200D01*
G01X111500Y851600D02*
Y843200D01*
X118625Y836075D01*
Y781625D01*
X116402Y779402D01*
G01X98900Y822900D02*
Y835000D01*
X98425Y835475D01*
Y871125D01*
X101500Y874200D01*
G01X100300Y841000D02*
X106104D01*
X106404Y840700D01*
G01X111500Y851600D02*
Y860300D01*
X113400Y862200D01*
G01X107164Y862285D02*
X103453D01*
X102300Y863438D01*
G01X146500Y953030D02*
X144627Y951157D01*
X142223D01*
X141125Y952255D01*
Y987335D01*
X122900Y1005560D01*
Y1007400D01*
G01X149772Y954121D02*
Y954380D01*
X147000Y957152D01*
Y987700D01*
X127500Y1007200D01*
Y1014900D01*
X127200Y1015200D01*
G01X128700Y1408000D02*
Y1095800D01*
X137401Y1087099D01*
Y1079633D01*
X137400Y1079632D01*
Y1076110D01*
X137401Y1076109D01*
Y1022649D01*
X139250Y1020800D01*
Y1012050D01*
X161100Y990200D01*
X165173D01*
X167550Y987823D01*
Y849975D01*
X148650Y831075D01*
Y734250D01*
X148879Y734021D01*
Y698879D01*
X148825Y698825D01*
Y689975D01*
X150975Y687825D01*
Y687778D01*
X150978Y687775D01*
G01X119500Y1261000D02*
X122692Y1257808D01*
G01X119000Y1255968D02*
X124000Y1250968D01*
Y1247600D01*
G01X109500Y1438000D02*
X103500Y1432000D01*
X102600D01*
X101600Y1431000D01*
G01X98500Y1428400D02*
X99000D01*
X101600Y1431000D01*
G01X169606Y234409D02*
Y234410D01*
X174696Y239500D01*
X182200D01*
X198276Y255576D01*
Y408353D01*
X203175Y413252D01*
Y481901D01*
X196325Y488751D01*
Y528551D01*
X182588Y542288D01*
G01X169606Y244409D02*
Y244410D01*
X174096Y248900D01*
X179825D01*
X196525Y265600D01*
Y420125D01*
X198325Y421925D01*
Y438402D01*
X200500Y440577D01*
Y477900D01*
X189825Y488575D01*
Y520673D01*
X186950Y523548D01*
Y533550D01*
X184003Y536497D01*
G01X160000Y562500D02*
Y560500D01*
X184003Y536497D01*
G01X142500Y1420500D02*
Y1101000D01*
X149000Y1094500D01*
Y1029500D01*
X180000Y998500D01*
Y988400D01*
X184175Y984225D01*
Y949575D01*
X182325Y947725D01*
Y775901D01*
X168125Y761701D01*
Y730401D01*
X172300Y726226D01*
Y697600D01*
X181100Y688800D01*
Y644400D01*
X183800Y641700D01*
Y618300D01*
X151325Y585825D01*
Y564600D01*
X184325Y531600D01*
Y490275D01*
X192007Y482593D01*
G01X170349Y619949D02*
Y616449D01*
X154550Y600650D01*
X148250D01*
X144600Y597000D01*
X136500D01*
G01X138900Y650100D02*
X137300Y651700D01*
Y659700D01*
X132725Y664275D01*
Y669725D01*
X137500Y674500D01*
Y682500D01*
G01X142648Y665429D02*
X146000Y662077D01*
Y641400D01*
G01X152700Y618803D02*
Y621500D01*
X146000Y628200D01*
Y641400D01*
G01X139200Y653900D02*
Y661200D01*
X136973Y663427D01*
Y671473D01*
X141800Y676300D01*
G01X150978Y687775D02*
X151000Y687753D01*
Y673781D01*
X142648Y665429D01*
G01X146800Y1018900D02*
Y1017600D01*
X173900Y990500D01*
Y847300D01*
X155000Y828400D01*
Y736900D01*
X159700Y732200D01*
Y692700D01*
X159450Y692450D01*
Y682950D01*
X159525Y682875D01*
Y675362D01*
X151432Y667269D01*
Y661741D01*
G01X148995Y658568D02*
Y667732D01*
X157475Y676212D01*
Y682025D01*
X157400Y682100D01*
Y693400D01*
X157567Y693567D01*
Y729267D01*
X157600Y729300D01*
Y731300D01*
X153200Y735700D01*
Y735800D01*
X152900Y736100D01*
Y829300D01*
X158700Y835100D01*
X158800D01*
X165900Y842200D01*
Y842300D01*
X171800Y848200D01*
Y989700D01*
X166600Y994900D01*
X166500D01*
X144700Y1016700D01*
Y1016800D01*
X143900Y1017600D01*
Y1022700D01*
G01X150700Y691700D02*
Y694200D01*
X152000Y695500D01*
Y695688D01*
G01X153192Y705890D02*
Y696880D01*
X152000Y695688D01*
G01X155000Y974500D02*
Y966900D01*
X158500Y963400D01*
Y898700D01*
X157800Y898000D01*
G01X147500Y900500D02*
X147625Y900625D01*
Y945125D01*
X153000Y950500D01*
Y952200D01*
X152747Y952453D01*
Y952474D01*
G01X135601Y1416200D02*
Y1099099D01*
X143701Y1090999D01*
Y1078721D01*
X143703Y1078719D01*
Y1026401D01*
X143725Y1026379D01*
Y1026378D01*
X143727Y1026376D01*
Y1025950D01*
X146075Y1023602D01*
Y1023600D01*
X146700Y1022975D01*
Y1019000D01*
X146800Y1018900D01*
G01X134500Y1420000D02*
X133551Y1419051D01*
Y1097549D01*
X141651Y1089449D01*
Y1077871D01*
X141653Y1077869D01*
Y1025551D01*
X141675Y1025529D01*
Y1025528D01*
X141677Y1025526D01*
Y1025100D01*
X143900Y1022877D01*
Y1022700D01*
G54D14*
X27559Y157480D03*
Y629921D03*
X17716Y1338583D03*
X27559Y1811023D03*
X179134Y78740D03*
X179133Y570866D03*
X179134Y1161417D03*
Y1889764D03*
G54D15*
X31299Y230866D03*
Y220866D03*
Y210866D03*
Y338563D03*
Y358563D03*
Y348563D03*
Y903917D03*
Y923917D03*
Y913917D03*
Y1054587D03*
Y1044587D03*
Y1064587D03*
Y1619941D03*
Y1609941D03*
Y1629941D03*
Y1757638D03*
Y1747638D03*
Y1737638D03*
G54D16*
X26450Y274750D03*
X25500Y321200D03*
X21600Y333800D03*
X29500Y343500D03*
X23100Y342400D03*
X23400Y353500D03*
X29500Y410500D03*
X14000Y476000D03*
X28800Y533700D03*
X5304Y548800D03*
Y528900D03*
X5094Y574500D03*
X29500Y586500D03*
X23450Y577491D03*
X25148Y570800D03*
X27000Y573800D03*
X4594Y749000D03*
Y714000D03*
X5094Y1354500D03*
X26700Y1529800D03*
X28000Y1596800D03*
X13300Y1644300D03*
X10500Y1648800D03*
X13300Y1689600D03*
X19542Y1710518D03*
X29100Y1721550D03*
X19200Y1707000D03*
X25000Y1763800D03*
X26750Y1791100D03*
X27400Y1899400D03*
X70454Y60031D03*
X64500Y53000D03*
X64000Y67553D03*
X74000Y60500D03*
X79000Y65500D03*
X75000Y67500D03*
X81500Y75500D03*
X63500Y63500D03*
X59600Y125800D03*
X75300Y155300D03*
X49924Y153261D03*
X53000Y171500D03*
X65000Y166300D03*
X60350Y151950D03*
X39300Y181100D03*
X63500Y179300D03*
X53400Y191300D03*
X39300Y175500D03*
X43700Y181200D03*
X43400Y174325D03*
X32425Y177900D03*
X52700Y162300D03*
X64400Y183400D03*
X52500Y175200D03*
X70500Y190200D03*
X54400Y217000D03*
X65200Y207850D03*
X57424Y232974D03*
X42720Y233990D03*
X65000Y241500D03*
Y235400D03*
X54200Y220700D03*
Y207850D03*
X51700Y234800D03*
X41100Y231000D03*
X71400Y208150D03*
X69900Y236600D03*
X77900Y229034D03*
X70600Y217600D03*
X74800Y231800D03*
X69400Y226100D03*
X61300Y229400D03*
X38000Y228500D03*
X75300Y211300D03*
X72100Y221700D03*
X49700Y209700D03*
X53500Y199700D03*
X47800Y199200D03*
X64000Y199700D03*
X60300Y275700D03*
X57500Y268500D03*
X68000Y268000D03*
X70600Y250500D03*
X48500Y248600D03*
X42500Y254100D03*
X58936Y256289D03*
X36000Y260386D03*
X42500Y260200D03*
X34200Y284800D03*
X52500Y248500D03*
X32600Y290500D03*
X50800Y266400D03*
X54000Y275600D03*
X45800Y277800D03*
X43400Y272300D03*
X32675Y299500D03*
X78000Y429500D03*
X34000Y448000D03*
X33200Y468900D03*
X52100Y513100D03*
X46500Y511000D03*
X46000Y516000D03*
X51000Y529500D03*
X71445Y532192D03*
X72397Y528297D03*
X77800Y540300D03*
X33450Y574300D03*
X63400Y581400D03*
X49700Y568900D03*
X66000Y550500D03*
X65000Y561500D03*
X78400Y583700D03*
X70350Y558850D03*
X54600Y573400D03*
X75571Y692496D03*
X53000Y673500D03*
X57684Y697639D03*
X64000Y666600D03*
X66200Y653500D03*
X82000Y652000D03*
X52500Y682500D03*
X78494Y697835D03*
X53000Y695100D03*
X39800Y681400D03*
X43388Y694286D03*
X44500Y697500D03*
X60900Y670200D03*
X60500Y682540D03*
X76100Y686900D03*
X73000Y728000D03*
X69000Y726800D03*
X71500Y735500D03*
X73500Y732000D03*
X49500Y703500D03*
X46500Y705500D03*
X57500Y844500D03*
X72400Y822900D03*
X51200Y827000D03*
X61207Y828350D03*
X49600Y889400D03*
X55700Y880000D03*
X59500Y881600D03*
X57500Y890300D03*
X56000Y885500D03*
X64600Y882700D03*
X61600Y885200D03*
X67200Y888800D03*
X54300Y915500D03*
X54000Y996500D03*
X70800Y990500D03*
X57500Y987800D03*
Y984300D03*
X53800Y1006200D03*
X53500Y1025500D03*
X56000Y1021500D03*
X54500Y1035500D03*
X51000Y1018000D03*
X64500Y1099000D03*
X37500Y1099823D03*
X70500Y1161500D03*
X73163Y1158780D03*
X71100Y1171000D03*
X68800Y1178800D03*
X39400Y1381300D03*
X44500Y1380500D03*
X45500Y1400000D03*
X45000Y1428000D03*
X80000Y1472000D03*
X36400Y1523400D03*
X67700Y1568700D03*
X43500Y1620700D03*
X42700Y1606000D03*
X38400Y1596700D03*
X42500Y1673000D03*
X35500Y1670500D03*
X43600Y1668300D03*
X43300Y1646600D03*
X31400Y1648200D03*
X45500Y1690000D03*
X41500Y1692000D03*
X44500Y1678000D03*
X40300Y1703900D03*
X44100Y1685200D03*
X34000Y1691500D03*
X45300Y1776300D03*
X52500Y1756000D03*
X62000Y1877000D03*
X57900Y1899800D03*
X65300Y1886600D03*
X55900Y1881500D03*
X38700Y1893800D03*
X41500Y1889500D03*
X60300Y1892300D03*
X47000Y1886200D03*
X79900Y1923000D03*
X91500Y88500D03*
X97000Y51500D03*
X115500Y59500D03*
X98500Y73000D03*
X109000Y76500D03*
X115000D03*
X99500Y61000D03*
X89500Y49500D03*
X109500Y62000D03*
X84500Y56500D03*
X92500Y73000D03*
X88253Y65500D03*
X93500Y101500D03*
X93900Y111800D03*
X93000Y107000D03*
X91000Y97000D03*
X91500Y92500D03*
X104500Y101000D03*
X112000D03*
X117600Y234900D03*
X122100Y230100D03*
X85676Y231100D03*
X127200Y246000D03*
X122500Y441000D03*
X108100Y477650D03*
X91300Y528200D03*
X108900Y541300D03*
X102700Y541000D03*
X87700Y528000D03*
X132500Y539621D03*
X129000Y597000D03*
X124200Y568400D03*
X119800Y568300D03*
X88000Y586500D03*
X101000Y583000D03*
X96000Y588000D03*
X89000Y595000D03*
X87000Y591000D03*
X121000Y581500D03*
X124900Y582000D03*
X91300Y577000D03*
X92200Y553800D03*
X106300Y553200D03*
X116000Y596900D03*
X113655Y599363D03*
X110400Y550800D03*
X128900Y580500D03*
X122300Y575000D03*
X115300Y551800D03*
X131135Y639554D03*
X84200Y643865D03*
X87000Y648000D03*
X130000Y700500D03*
X122500D03*
X114500D03*
X105500Y702500D03*
X93000Y698500D03*
X88500Y700000D03*
X98000Y698500D03*
X86597Y681103D03*
X100200Y663900D03*
X122500Y653650D03*
X117400Y653100D03*
X118127Y663400D03*
X109005Y665890D03*
X114000Y663350D03*
X83850Y678109D03*
X91250Y704700D03*
X130000Y753000D03*
Y746000D03*
X119500Y746500D03*
Y739500D03*
X113500Y729000D03*
Y736000D03*
Y747000D03*
Y721000D03*
X106000Y709000D03*
X98000Y703000D03*
Y708000D03*
X86500Y723500D03*
X130000Y764000D03*
X119500Y757500D03*
X113500Y756000D03*
X118700Y840700D03*
X98900Y822900D03*
X114900Y824100D03*
X106404Y840700D03*
X100300Y841000D03*
X111500Y851600D03*
X101500Y874200D03*
X102300Y863438D03*
X107164Y862285D03*
X113400Y862200D03*
X125400Y983600D03*
Y992000D03*
X97300Y990800D03*
X83500Y976300D03*
Y972800D03*
X83000Y979800D03*
X94000Y971800D03*
X104000Y1049500D03*
X127200Y1015200D03*
X104000Y1062500D03*
X82094Y1112500D03*
X105000Y1181000D03*
X119500Y1261000D03*
X119000Y1255968D03*
X128700Y1408000D03*
X125000Y1398500D03*
X100860Y1402260D03*
X111000Y1394000D03*
X125100Y1402500D03*
X131174Y1412700D03*
X83200Y1455500D03*
X89000Y1428171D03*
X110000Y1429500D03*
X132000Y1436500D03*
X112750Y1491250D03*
X121000Y1506500D03*
X113000D03*
X117000D03*
X109000D03*
X133000Y1505500D03*
X128999Y1506499D03*
X125000Y1506500D03*
X132300Y1491100D03*
X108500Y1569000D03*
X83000Y1619703D03*
X113200Y1622800D03*
Y1619300D03*
X83050Y1616000D03*
X91100Y1922800D03*
X128900Y1923300D03*
X104600Y1923400D03*
X149500Y52000D03*
X135500Y441000D03*
X146960Y432400D03*
X142000Y478500D03*
X165300Y481100D03*
X144000Y509500D03*
X166100Y527900D03*
X147000Y529900D03*
X162500Y527900D03*
X159850Y541800D03*
X182588Y542288D03*
X159250Y590250D03*
X154600Y581500D03*
X133500Y575500D03*
X145800Y594400D03*
X137000Y589900D03*
X133500Y582000D03*
X134600Y586700D03*
X156300Y552100D03*
X142500Y550000D03*
X135000Y561500D03*
X142100Y581400D03*
X160000Y562500D03*
X147900Y588100D03*
X138900Y650100D03*
X174196Y628196D03*
X139200Y653900D03*
X150978Y687775D03*
X142648Y665429D03*
X165433Y692372D03*
X134600Y665600D03*
X161000Y674000D03*
X157500Y664500D03*
X149000Y677000D03*
X155200Y679500D03*
X161500Y691700D03*
X150700D03*
X166000Y751500D03*
X170000Y745500D03*
X161600Y739800D03*
X161500Y747500D03*
X146000Y726000D03*
X165900Y717300D03*
X147000Y703000D03*
X146000Y738000D03*
X175100Y710000D03*
X158600Y752600D03*
X153192Y705890D03*
X146000Y755000D03*
Y765500D03*
Y796500D03*
Y782500D03*
X166000Y760000D03*
X166500Y775500D03*
X161500Y759000D03*
Y768000D03*
Y778000D03*
X146500Y812000D03*
X146000Y824000D03*
X180000Y856000D03*
X162000Y817500D03*
X174000Y834500D03*
X168000Y830000D03*
X180000Y872500D03*
X179500Y884000D03*
X179900Y900900D03*
X157800Y898000D03*
X147500Y900500D03*
X179900Y925700D03*
X179800Y941400D03*
X180000Y912500D03*
X143000Y953032D03*
X146500Y953030D03*
X149772Y954121D03*
X152747Y952474D03*
X163200Y985200D03*
X163100Y978600D03*
X149800Y1008700D03*
X179000Y1005000D03*
X180000Y960400D03*
X180500Y973200D03*
X150500Y976500D03*
X155000Y974500D03*
X155500Y1030000D03*
X153500Y1033500D03*
X151500Y1030500D03*
X163000Y1042500D03*
X159500Y1062000D03*
X135601Y1416200D03*
X146500Y1397100D03*
X155900D03*
X139900Y1415100D03*
X134500Y1420000D03*
X169000Y1426750D03*
X158500Y1466500D03*
X151500Y1438500D03*
X157500Y1454800D03*
X142500Y1420500D03*
X142000Y1494800D03*
X147500Y1498000D03*
X153500Y1496500D03*
X135008Y1508245D03*
X143518Y1567520D03*
X177500Y1569500D03*
X141500Y1621600D03*
X141300Y1625000D03*
X169876Y1626303D03*
X173270Y1626517D03*
X170000Y1920500D03*
X162100Y1912000D03*
X151900Y1891400D03*
X146300Y1913700D03*
X142400Y1923800D03*
X176700Y1923900D03*
X177700Y1912800D03*
X152500Y1883100D03*
X157900Y1923100D03*
X133500Y1906500D03*
X201500Y165000D03*
X191400Y432405D03*
X202210Y638500D03*
X201500Y691500D03*
X202500Y666000D03*
X201500Y726500D03*
X202500Y755500D03*
X201500Y777000D03*
X201389Y797000D03*
X202500Y822000D03*
Y846500D03*
X202000Y859500D03*
Y890000D03*
X202210Y903500D03*
X202000Y875000D03*
X202500Y945500D03*
X202000Y918000D03*
X201500Y931500D03*
X202500Y1006000D03*
Y977500D03*
Y962000D03*
X201500Y991000D03*
X202000Y1037000D03*
Y1052000D03*
X201500Y1019000D03*
X201389Y1067000D03*
X201500Y1082500D03*
X195000Y1112000D03*
X201500Y1147000D03*
X202000Y1212000D03*
X202500Y1179000D03*
X202000Y1246000D03*
X201500Y1310000D03*
X202500Y1280000D03*
X201500Y1359500D03*
X200700Y1348500D03*
X201700Y1388300D03*
X201500Y1413000D03*
X202400Y1444000D03*
X201389Y1425500D03*
X202210Y1462000D03*
X201500Y1569000D03*
X202000Y1537500D03*
X202210Y1554000D03*
X187500Y1559500D03*
X196500Y1606500D03*
X191700Y1652700D03*
X192500Y1648000D03*
X192650Y1641500D03*
X200500Y1876500D03*
X184500Y1920500D03*
X201200Y1890500D03*
X201100Y1908800D03*
G54D17*
X80709Y161889D03*
Y171889D03*
Y181889D03*
Y191889D03*
Y204409D03*
Y214409D03*
Y224409D03*
Y234409D03*
Y244409D03*
Y256929D03*
Y266929D03*
Y276929D03*
Y286929D03*
X110709Y161889D03*
Y171889D03*
X100709Y161889D03*
Y171889D03*
X90709Y161889D03*
Y171889D03*
X110709Y181889D03*
Y191889D03*
X100709Y181889D03*
Y191889D03*
X90709Y181889D03*
Y191889D03*
X110709Y204409D03*
Y214409D03*
Y224409D03*
Y234409D03*
Y244409D03*
X100709Y204409D03*
Y214409D03*
Y224409D03*
Y234409D03*
Y244409D03*
X90709Y204409D03*
Y214409D03*
Y224409D03*
Y234409D03*
Y244409D03*
X110709Y256929D03*
Y266929D03*
X100709Y256929D03*
Y266929D03*
X90709Y256929D03*
Y266929D03*
X110709Y276929D03*
Y286929D03*
X100709Y276929D03*
Y286929D03*
X90709Y276929D03*
Y286929D03*
X179606Y161889D03*
Y171889D03*
X169606Y161889D03*
Y171889D03*
X159606Y161889D03*
Y171889D03*
X149606Y161889D03*
Y171889D03*
X179606Y181889D03*
Y191889D03*
X169606Y181889D03*
Y191889D03*
X159606Y181889D03*
Y191889D03*
X149606Y181889D03*
Y191889D03*
X179606Y204409D03*
Y214409D03*
Y224409D03*
Y234409D03*
Y244409D03*
X169606Y204409D03*
Y214409D03*
Y224409D03*
Y234409D03*
Y244409D03*
X159606Y204409D03*
Y214409D03*
Y224409D03*
Y234409D03*
Y244409D03*
X149606Y204409D03*
Y214409D03*
Y224409D03*
Y234409D03*
Y244409D03*
X179606Y256929D03*
Y266929D03*
X169606Y256929D03*
Y266929D03*
X159606Y256929D03*
Y266929D03*
X149606Y256929D03*
Y266929D03*
X179606Y276929D03*
Y286929D03*
X169606Y276929D03*
Y286929D03*
X159606Y276929D03*
Y286929D03*
X149606Y276929D03*
Y286929D03*
G54D18*
X96457Y1747835D03*
Y1823031D03*
X178937Y1328740D03*
X161417Y1747835D03*
Y1823031D03*
G54D19*
G01X-448201Y-82763D02*
Y-162763D01*
G01Y-118263D02*
X752899D01*
G01X-448201Y-162763D02*
X752899D01*
G01X-452201Y-66763D02*
G02I-12000J0D01*
G01X-457351D02*
G02I-6850J0D01*
G01X-464201Y-82763D02*
Y-50763D01*
G01X-448201Y-66763D02*
X-480201D01*
G01X-448201Y-82763D02*
X752899D01*
G01X-34601D02*
Y-162763D01*
G01X26450Y274750D02*
X26374Y274826D01*
X26373D01*
X23900Y277299D01*
Y319600D01*
X25500Y321200D01*
G01X28050Y256950D02*
X27300Y257700D01*
Y273900D01*
X26450Y274750D01*
G01X42720Y233990D02*
X28050Y248660D01*
Y256950D01*
G01X25500Y321200D02*
X18421Y328279D01*
Y447941D01*
X16554Y449808D01*
Y466254D01*
X28100Y477800D01*
Y528100D01*
X40000Y540000D01*
Y579000D01*
X53000Y592000D01*
Y673500D01*
G01X64500Y1165700D02*
X63900Y1166300D01*
Y1326100D01*
X9221Y1380779D01*
Y1489321D01*
X11300Y1491400D01*
Y1642300D01*
X13300Y1644300D01*
G01D02*
Y1689600D01*
G01X65200Y207850D02*
X63550D01*
X54400Y217000D01*
G01X57424Y232974D02*
Y220024D01*
X54400Y217000D01*
G01X65000Y241500D02*
Y235400D01*
G01X70600Y250500D02*
X70100Y251000D01*
Y265900D01*
X68000Y268000D01*
G01X78000Y429500D02*
X78500Y430000D01*
X111500D01*
X122500Y441000D01*
G01X77800Y540300D02*
Y532227D01*
X77842Y532185D01*
Y529781D01*
X75000Y526939D01*
Y446444D01*
X63096Y434540D01*
G01X87700Y528000D02*
Y527273D01*
X89800Y525173D01*
Y502774D01*
X78200Y491174D01*
Y481700D01*
G01X77800Y540300D02*
Y543500D01*
X112501Y578201D01*
X126601D01*
X128900Y580500D01*
G01X53000Y673500D02*
Y677359D01*
X56710Y681069D01*
G01X67700Y1568700D02*
Y1524400D01*
X81900Y1510200D01*
G01X102899Y-82763D02*
Y-162763D01*
G01X122500Y441000D02*
X117400D01*
X103525Y454875D01*
Y523425D01*
X105300Y525200D01*
G01X91300Y528200D02*
Y528199D01*
X93000Y526499D01*
Y501448D01*
X82000Y490448D01*
Y483600D01*
G01X110400Y550800D02*
X105300Y545700D01*
Y525200D01*
G01X122300Y575000D02*
X123400D01*
X127900Y570500D01*
Y544221D01*
X132500Y539621D01*
G01X135500Y441000D02*
X136577D01*
X148650Y453073D01*
Y523471D01*
X132500Y539621D01*
G01X87200Y1440000D02*
X87900D01*
X91300Y1436600D01*
Y1430300D01*
X89620Y1428620D01*
X89561D01*
X89112Y1428171D01*
X89000D01*
G01X99800Y1455600D02*
Y1452300D01*
X95859Y1448359D01*
G01X87200Y1440000D02*
X91400Y1444200D01*
X91700D01*
X95859Y1448359D01*
G01X152500Y1456000D02*
X148700D01*
X144700Y1460000D01*
Y1460002D01*
X113452Y1491250D01*
X112750D01*
G01X81900Y1510200D02*
X95500Y1496600D01*
X126800D01*
X132300Y1491100D01*
G01X108500Y1556500D02*
Y1569000D01*
G01Y1556500D02*
Y1544900D01*
X133900Y1519500D01*
X134000D01*
G01X191400Y432405D02*
X191100Y432705D01*
Y433232D01*
X189332Y435000D01*
X149560D01*
X146960Y432400D01*
G01X169200Y482800D02*
Y489800D01*
X166100Y492900D01*
Y527900D01*
G01X165300Y481100D02*
Y488900D01*
X162500Y491700D01*
Y527900D01*
G01X179300Y530000D02*
X179425Y529875D01*
Y450325D01*
X191400Y438350D01*
Y432405D01*
G01X159850Y541800D02*
X167500D01*
X179300Y530000D01*
G01X158600Y752600D02*
Y737300D01*
X162500Y733400D01*
Y701200D01*
X173100Y690600D01*
Y629292D01*
X174196Y628196D01*
G01X139900Y1415100D02*
X139000Y1414200D01*
Y1100500D01*
X146500Y1093000D01*
Y1027102D01*
X176675Y996927D01*
Y844775D01*
X158600Y826700D01*
Y752600D01*
G01X139900Y1415100D02*
Y1442378D01*
X152500Y1454978D01*
Y1456000D01*
G01D02*
Y1458898D01*
X158500Y1464898D01*
Y1466500D01*
G01X134000Y1519500D02*
Y1519000D01*
X142000Y1511000D01*
Y1494800D01*
G01X147500Y1498000D02*
Y1505000D01*
G01X143518Y1540000D02*
Y1525482D01*
X147500Y1521500D01*
Y1505000D01*
G01X153500Y1496500D02*
X157000Y1500000D01*
Y1528000D01*
G01X143518Y1567520D02*
Y1540000D01*
G01X177500Y1569500D02*
X173398D01*
X157000Y1553102D01*
Y1528000D01*
G01X217899Y-82763D02*
Y-162763D01*
G01X385399Y-82763D02*
Y-162763D01*
G01X555399Y-82763D02*
Y-162763D01*
G01X752899Y-82763D02*
Y-162763D01*
G01X780899Y-66763D02*
G02I-12000J0D01*
G01X775749D02*
G02I-6850J0D01*
G01X768899Y-82763D02*
Y-50763D01*
G01X784899Y-66763D02*
X752899D01*
M02*
